FILE_TYPE = MACRO_DRAWING;
SET COLOR_WIRE YELLOW;
SET COLOR_PROP MONO;
SET COLOR_DOT WHITE;
SET COLOR_ARC YELLOW;
SET COLOR_BODY GREEN;
SET COLOR_NOTE MONO;
SET PROP_DISPLAY VALUE;
SET PAGE_NUMBER P269;
FORCEADD RES..2
R 1
(-6100 2900);
FORCEPROP 1 LASTPIN (-6200 2900) $PN 1
J 0
(-6187 2905);
DISPLAY 0.617021 (-6187 2905);
PAINT WHITE (-6187 2905);
FORCEPROP 1 LASTPIN (-6000 2900) $PN 2
J 0
(-6035 2905);
DISPLAY 0.617021 (-6035 2905);
PAINT WHITE (-6035 2905);
FORCEPROP 1 LAST TOLERANCE 1%
J 0
(-6000 2820);
DISPLAY 0.617021 (-6000 2820);
PAINT SKYBLUE (-6000 2820);
FORCEPROP 1 LAST MATERIAL CHIP
J 0
(-5800 2765);
DISPLAY 0.617021 (-5800 2765);
PAINT SKYBLUE (-5800 2765);
FORCEPROP 1 LAST PART_NUMBER G21796-026
J 0
(-6050 2765);
DISPLAY 0.617021 (-6050 2765);
PAINT BLUE (-6050 2765);
FORCEPROP 1 LAST PACK_TYPE 0402
J 0
(-6200 2765);
DISPLAY 0.617021 (-6200 2765);
PAINT SKYBLUE (-6200 2765);
FORCEPROP 1 LAST WATTAGE 1/16W
J 0
(-6350 2765);
DISPLAY 0.617021 (-6350 2765);
PAINT SKYBLUE (-6350 2765);
FORCEPROP 1 LAST LOCATION R25W167
J 0
(-6350 2820);
DISPLAY 0.617021 (-6350 2820);
PAINT AQUA (-6350 2820);
FORCEPROP 1 LAST VALUE 1.00K
J 0
(-6150 2820);
DISPLAY 0.617021 (-6150 2820);
PAINT SKYBLUE (-6150 2820);
FORCEPROP 2 LAST ROOM PROC_RSTS_PGOODS
R 1
J 0
(-5875 2925);
DISPLAY 1.617021 (-5875 2925);
PAINT WHITE (-5875 2925);
DISPLAY INVISIBLE (-5875 2925);
FORCEPROP 2 LAST $SEC 1
R 1
J 0
(-6325 2950);
DISPLAY 1.510638 (-6325 2950);
PAINT MONO (-6325 2950);
DISPLAY INVISIBLE (-6325 2950);
FORCEPROP 2 LAST CDS_SEC 1
R 1
J 0
(-6325 2950);
DISPLAY 2.276596 (-6325 2950);
PAINT ORANGE (-6325 2950);
DISPLAY INVISIBLE (-6325 2950);
FORCEPROP 2 LAST CDS_LIB mstr_discrete
R 1
J 0
(-6100 2900);
DISPLAY 1.617021 (-6100 2900);
PAINT ORANGE (-6100 2900);
DISPLAY INVISIBLE (-6100 2900);
FORCEPROP 2 LAST BOM_COST PROC_SIDEBAND
R 1
J 0
(-6100 2900);
DISPLAY 1.617021 (-6100 2900);
PAINT WHITE (-6100 2900);
DISPLAY INVISIBLE (-6100 2900);
FORCEPROP 2 LAST CDS_LOCATION R25W167
R 1
J 0
(-6225 2945);
DISPLAY 0.617021 (-6225 2945);
PAINT AQUA (-6225 2945);
DISPLAY INVISIBLE (-6225 2945);
FORCEPROP 1 LAST PATH I10
R 1
J 0
(-6275 2950);
DISPLAY 0.978723 (-6275 2950);
PAINT WHITE (-6275 2950);
DISPLAY INVISIBLE (-6275 2950);
FORCEADD RES..2
R 1
(-4750 3500);
FORCEPROP 1 LAST LOCATION R25W168
J 0
(-4850 3545);
DISPLAY 0.617021 (-4850 3545);
PAINT AQUA (-4850 3545);
FORCEPROP 1 LAST PACK_TYPE 0402
J 0
(-4700 3440);
DISPLAY 0.617021 (-4700 3440);
PAINT SKYBLUE (-4700 3440);
FORCEPROP 1 LAST VALUE 1.00K
J 0
(-4650 3545);
DISPLAY 0.617021 (-4650 3545);
PAINT SKYBLUE (-4650 3545);
FORCEPROP 1 LAST PART_NUMBER G21796-026
J 0
(-4550 3440);
DISPLAY 0.617021 (-4550 3440);
PAINT BLUE (-4550 3440);
FORCEPROP 1 LAST MATERIAL CHIP
J 0
(-4300 3440);
DISPLAY 0.617021 (-4300 3440);
PAINT SKYBLUE (-4300 3440);
FORCEPROP 1 LAST WATTAGE 1/16W
J 0
(-4850 3440);
DISPLAY 0.617021 (-4850 3440);
PAINT SKYBLUE (-4850 3440);
FORCEPROP 1 LASTPIN (-4850 3500) $PN 1
J 0
(-4837 3505);
DISPLAY 0.617021 (-4837 3505);
PAINT WHITE (-4837 3505);
FORCEPROP 1 LAST TOLERANCE 1%
J 0
(-4500 3545);
DISPLAY 0.617021 (-4500 3545);
PAINT SKYBLUE (-4500 3545);
FORCEPROP 1 LASTPIN (-4650 3500) $PN 2
J 0
(-4685 3505);
DISPLAY 0.617021 (-4685 3505);
PAINT WHITE (-4685 3505);
FORCEPROP 2 LAST BOM_COST PROC_SIDEBAND
R 1
J 0
(-4750 3500);
DISPLAY 1.617021 (-4750 3500);
PAINT WHITE (-4750 3500);
DISPLAY INVISIBLE (-4750 3500);
FORCEPROP 2 LAST CDS_LIB mstr_discrete
R 1
J 0
(-4750 3500);
DISPLAY 1.617021 (-4750 3500);
PAINT ORANGE (-4750 3500);
DISPLAY INVISIBLE (-4750 3500);
FORCEPROP 2 LAST CDS_SEC 1
R 1
J 0
(-4975 3550);
DISPLAY 2.276596 (-4975 3550);
PAINT ORANGE (-4975 3550);
DISPLAY INVISIBLE (-4975 3550);
FORCEPROP 2 LAST $SEC 1
R 1
J 0
(-4975 3550);
DISPLAY 1.510638 (-4975 3550);
PAINT MONO (-4975 3550);
DISPLAY INVISIBLE (-4975 3550);
FORCEPROP 2 LAST ROOM PROC_RSTS_PGOODS
R 1
J 0
(-4525 3525);
DISPLAY 1.617021 (-4525 3525);
PAINT WHITE (-4525 3525);
DISPLAY INVISIBLE (-4525 3525);
FORCEPROP 2 LAST CDS_LOCATION R25W168
R 1
J 0
(-4875 3545);
DISPLAY 0.617021 (-4875 3545);
PAINT AQUA (-4875 3545);
DISPLAY INVISIBLE (-4875 3545);
FORCEPROP 1 LAST PATH I11
R 1
J 0
(-4925 3550);
DISPLAY 0.978723 (-4925 3550);
PAINT WHITE (-4925 3550);
DISPLAY INVISIBLE (-4925 3550);
FORCEADD RES..2
R 1
(-4750 3700);
FORCEPROP 1 LAST LOCATION R25W169
J 0
(-4850 3745);
DISPLAY 0.617021 (-4850 3745);
PAINT AQUA (-4850 3745);
FORCEPROP 1 LAST WATTAGE 1/16W
J 0
(-4850 3640);
DISPLAY 0.617021 (-4850 3640);
PAINT SKYBLUE (-4850 3640);
FORCEPROP 1 LAST VALUE 1.00K
J 0
(-4650 3745);
DISPLAY 0.617021 (-4650 3745);
PAINT SKYBLUE (-4650 3745);
FORCEPROP 1 LAST PACK_TYPE 0402
J 0
(-4700 3640);
DISPLAY 0.617021 (-4700 3640);
PAINT SKYBLUE (-4700 3640);
FORCEPROP 1 LAST PART_NUMBER G21796-026
J 0
(-4550 3640);
DISPLAY 0.617021 (-4550 3640);
PAINT BLUE (-4550 3640);
FORCEPROP 1 LAST MATERIAL CHIP
J 0
(-4300 3640);
DISPLAY 0.617021 (-4300 3640);
PAINT SKYBLUE (-4300 3640);
FORCEPROP 1 LASTPIN (-4650 3700) $PN 2
J 0
(-4685 3705);
DISPLAY 0.617021 (-4685 3705);
PAINT WHITE (-4685 3705);
FORCEPROP 1 LASTPIN (-4850 3700) $PN 1
J 0
(-4837 3705);
DISPLAY 0.617021 (-4837 3705);
PAINT WHITE (-4837 3705);
FORCEPROP 1 LAST TOLERANCE 1%
J 0
(-4500 3745);
DISPLAY 0.617021 (-4500 3745);
PAINT SKYBLUE (-4500 3745);
FORCEPROP 2 LAST BOM_COST PROC_SIDEBAND
R 1
J 0
(-4750 3700);
DISPLAY 1.617021 (-4750 3700);
PAINT WHITE (-4750 3700);
DISPLAY INVISIBLE (-4750 3700);
FORCEPROP 2 LAST CDS_LIB mstr_discrete
R 1
J 0
(-4750 3700);
DISPLAY 1.617021 (-4750 3700);
PAINT ORANGE (-4750 3700);
DISPLAY INVISIBLE (-4750 3700);
FORCEPROP 2 LAST CDS_SEC 1
R 1
J 0
(-4975 3750);
DISPLAY 2.276596 (-4975 3750);
PAINT ORANGE (-4975 3750);
DISPLAY INVISIBLE (-4975 3750);
FORCEPROP 2 LAST $SEC 1
R 1
J 0
(-4975 3750);
DISPLAY 1.510638 (-4975 3750);
PAINT MONO (-4975 3750);
DISPLAY INVISIBLE (-4975 3750);
FORCEPROP 2 LAST ROOM PROC_RSTS_PGOODS
R 1
J 0
(-4525 3725);
DISPLAY 1.617021 (-4525 3725);
PAINT WHITE (-4525 3725);
DISPLAY INVISIBLE (-4525 3725);
FORCEPROP 2 LAST CDS_LOCATION R25W169
R 1
J 0
(-4875 3745);
DISPLAY 0.617021 (-4875 3745);
PAINT AQUA (-4875 3745);
DISPLAY INVISIBLE (-4875 3745);
FORCEPROP 1 LAST PATH I12
R 1
J 0
(-4925 3750);
DISPLAY 0.978723 (-4925 3750);
PAINT WHITE (-4925 3750);
DISPLAY INVISIBLE (-4925 3750);
FORCEADD RES..2
R 1
(-4750 3900);
FORCEPROP 1 LAST LOCATION R25W170
J 0
(-4850 3945);
DISPLAY 0.617021 (-4850 3945);
PAINT AQUA (-4850 3945);
FORCEPROP 1 LASTPIN (-4650 3900) $PN 2
J 0
(-4685 3905);
DISPLAY 0.617021 (-4685 3905);
PAINT WHITE (-4685 3905);
FORCEPROP 1 LASTPIN (-4850 3900) $PN 1
J 0
(-4837 3905);
DISPLAY 0.617021 (-4837 3905);
PAINT WHITE (-4837 3905);
FORCEPROP 1 LAST PART_NUMBER G21796-026
J 0
(-4550 3840);
DISPLAY 0.617021 (-4550 3840);
PAINT BLUE (-4550 3840);
FORCEPROP 1 LAST MATERIAL CHIP
J 0
(-4300 3840);
DISPLAY 0.617021 (-4300 3840);
PAINT SKYBLUE (-4300 3840);
FORCEPROP 1 LAST TOLERANCE 1%
J 0
(-4500 3945);
DISPLAY 0.617021 (-4500 3945);
PAINT SKYBLUE (-4500 3945);
FORCEPROP 1 LAST VALUE 1.00K
J 0
(-4650 3945);
DISPLAY 0.617021 (-4650 3945);
PAINT SKYBLUE (-4650 3945);
FORCEPROP 1 LAST PACK_TYPE 0402
J 0
(-4700 3840);
DISPLAY 0.617021 (-4700 3840);
PAINT SKYBLUE (-4700 3840);
FORCEPROP 1 LAST WATTAGE 1/16W
J 0
(-4850 3840);
DISPLAY 0.617021 (-4850 3840);
PAINT SKYBLUE (-4850 3840);
FORCEPROP 2 LAST BOM_COST PROC_SIDEBAND
R 1
J 0
(-4750 3900);
DISPLAY 1.617021 (-4750 3900);
PAINT WHITE (-4750 3900);
DISPLAY INVISIBLE (-4750 3900);
FORCEPROP 2 LAST CDS_LIB mstr_discrete
R 1
J 0
(-4750 3900);
DISPLAY 1.617021 (-4750 3900);
PAINT ORANGE (-4750 3900);
DISPLAY INVISIBLE (-4750 3900);
FORCEPROP 2 LAST CDS_SEC 1
R 1
J 0
(-4975 3950);
DISPLAY 2.276596 (-4975 3950);
PAINT ORANGE (-4975 3950);
DISPLAY INVISIBLE (-4975 3950);
FORCEPROP 2 LAST $SEC 1
R 1
J 0
(-4975 3950);
DISPLAY 1.510638 (-4975 3950);
PAINT MONO (-4975 3950);
DISPLAY INVISIBLE (-4975 3950);
FORCEPROP 2 LAST ROOM PROC_RSTS_PGOODS
R 1
J 0
(-4525 3925);
DISPLAY 1.617021 (-4525 3925);
PAINT WHITE (-4525 3925);
DISPLAY INVISIBLE (-4525 3925);
FORCEPROP 2 LAST CDS_LOCATION R25W170
R 1
J 0
(-4875 3945);
DISPLAY 0.617021 (-4875 3945);
PAINT AQUA (-4875 3945);
DISPLAY INVISIBLE (-4875 3945);
FORCEPROP 1 LAST PATH I13
R 1
J 0
(-4925 3950);
DISPLAY 0.978723 (-4925 3950);
PAINT WHITE (-4925 3950);
DISPLAY INVISIBLE (-4925 3950);
FORCEADD GND..1
(-4100 3425);
FORCEPROP 3 LASTPIN (-4100 3475) SIG_NAME GND\g
J 0
(-4090 3485);
DISPLAY 0.659574 (-4090 3485);
PAINT MONO (-4090 3485);
DISPLAY INVISIBLE (-4090 3485);
FORCEPROP 1 LAST VOLTAGE 0.0V
J 0
(-4145 3382);
DISPLAY 0.340426 (-4145 3382);
PAINT SKYBLUE (-4145 3382);
DISPLAY INVISIBLE (-4145 3382);
FORCEPROP 1 LAST SIZE 1B
J 0
(-4025 3375);
DISPLAY 1.893617 (-4025 3375);
PAINT GREEN (-4025 3375);
DISPLAY INVISIBLE (-4025 3375);
FORCEPROP 2 LAST CDS_LIB mstr_symbols
J 0
(-4100 3425);
PAINT ORANGE (-4100 3425);
DISPLAY INVISIBLE (-4100 3425);
FORCEPROP 1 LAST PATH I14
J 0
(-4025 3425);
DISPLAY 0.872340 (-4025 3425);
PAINT AQUA (-4025 3425);
DISPLAY INVISIBLE (-4025 3425);
FORCEPROP 1 LAST BODY_TYPE PLUMBING
J 0
(-4145 3382);
DISPLAY 0.340426 (-4145 3382);
PAINT GREEN (-4145 3382);
DISPLAY INVISIBLE (-4145 3382);
FORCEPROP 1 LAST HDL_POWER GND
J 0
(-4100 3575);
DISPLAY 1.595745 (-4100 3575);
PAINT GREEN (-4100 3575);
DISPLAY INVISIBLE (-4100 3575);
FORCEADD P3V3_STBY..1
(-6400 4100);
FORCEPROP 3 LASTPIN (-6400 4050) SIG_NAME P3V3_STBY\g
J 0
(-6390 4060);
DISPLAY 0.659574 (-6390 4060);
PAINT MONO (-6390 4060);
DISPLAY INVISIBLE (-6390 4060);
FORCEPROP 1 LAST SIZE 1B
J 0
(-6355 4122);
DISPLAY 0.340426 (-6355 4122);
PAINT GREEN (-6355 4122);
DISPLAY INVISIBLE (-6355 4122);
FORCEPROP 2 LAST CDS_LIB mstr_symbols
J 0
(-6400 4100);
PAINT MONO (-6400 4100);
DISPLAY INVISIBLE (-6400 4100);
FORCEPROP 1 LAST VOLTAGE 3.3V
J 0
(-6445 4057);
DISPLAY 0.340426 (-6445 4057);
PAINT SKYBLUE (-6445 4057);
DISPLAY INVISIBLE (-6445 4057);
FORCEPROP 1 LAST PATH I15
J 0
(-6355 4102);
DISPLAY 0.340426 (-6355 4102);
PAINT GREEN (-6355 4102);
DISPLAY INVISIBLE (-6355 4102);
FORCEPROP 1 LAST BODY_TYPE PLUMBING
J 0
(-6445 4057);
DISPLAY 0.340426 (-6445 4057);
PAINT GREEN (-6445 4057);
DISPLAY INVISIBLE (-6445 4057);
FORCEPROP 1 LAST HDL_POWER P3V3_STBY
J 0
(-6700 3975);
DISPLAY 0.872340 (-6700 3975);
PAINT ORANGE (-6700 3975);
DISPLAY INVISIBLE (-6700 3975);
FORCEADD OFFPAGE..1
(-7750 5450);
FORCEPROP 2 LAST $XR0 255 
J 0
(-8002 5450);
DISPLAY 0.638298 (-8002 5450);
PAINT MONO (-8002 5450);
FORCEPROP 2 LAST PATH I16
J 0
(-8025 5500);
DISPLAY 1.021277 (-8025 5500);
PAINT ORANGE (-8025 5500);
DISPLAY INVISIBLE (-8025 5500);
FORCEPROP 2 LAST CDS_LIB mstr_standard
J 0
(-7750 5450);
PAINT ORANGE (-7750 5450);
DISPLAY INVISIBLE (-7750 5450);
FORCEPROP 1 LAST OFFPAGE TRUE
J 0
(-7425 5325);
DISPLAY 1.404255 (-7425 5325);
PAINT GREEN (-7425 5325);
DISPLAY INVISIBLE (-7425 5325);
FORCEPROP 1 LAST COMMENT_BODY TRUE
J 0
(-7625 5350);
DISPLAY 1.404255 (-7625 5350);
PAINT PEACH (-7625 5350);
DISPLAY INVISIBLE (-7625 5350);
FORCEADD OFFPAGE..1
(-7750 5500);
FORCEPROP 2 LAST $XR0 255 
J 0
(-8002 5500);
DISPLAY 0.638298 (-8002 5500);
PAINT MONO (-8002 5500);
FORCEPROP 2 LAST CDS_LIB mstr_standard
J 0
(-7750 5500);
PAINT ORANGE (-7750 5500);
DISPLAY INVISIBLE (-7750 5500);
FORCEPROP 2 LAST PATH I17
J 0
(-8025 5550);
DISPLAY 1.021277 (-8025 5550);
PAINT ORANGE (-8025 5550);
DISPLAY INVISIBLE (-8025 5550);
FORCEPROP 1 LAST OFFPAGE TRUE
J 0
(-7425 5375);
DISPLAY 1.404255 (-7425 5375);
PAINT GREEN (-7425 5375);
DISPLAY INVISIBLE (-7425 5375);
FORCEPROP 1 LAST COMMENT_BODY TRUE
J 0
(-7625 5400);
DISPLAY 1.404255 (-7625 5400);
PAINT PEACH (-7625 5400);
DISPLAY INVISIBLE (-7625 5400);
FORCEADD RES..2
(-7650 6050);
FORCEPROP 1 LAST LOCATION R25W177
J 0
(-7605 6200);
DISPLAY 0.617021 (-7605 6200);
PAINT AQUA (-7605 6200);
FORCEPROP 1 LASTPIN (-7650 6150) $PN 1
J 0
(-7645 6112);
DISPLAY 0.617021 (-7645 6112);
PAINT WHITE (-7645 6112);
FORCEPROP 1 LAST TOLERANCE 1%
J 0
(-7605 6100);
DISPLAY 0.617021 (-7605 6100);
PAINT SKYBLUE (-7605 6100);
FORCEPROP 1 LAST VALUE 1.00K
J 0
(-7605 6150);
DISPLAY 0.617021 (-7605 6150);
PAINT SKYBLUE (-7605 6150);
FORCEPROP 1 LASTPIN (-7650 5950) $PN 2
J 0
(-7645 5960);
DISPLAY 0.617021 (-7645 5960);
PAINT WHITE (-7645 5960);
FORCEPROP 1 LAST WATTAGE 1/16W
J 0
(-7610 6050);
DISPLAY 0.617021 (-7610 6050);
PAINT SKYBLUE (-7610 6050);
FORCEPROP 1 LAST MATERIAL CHIP
J 0
(-7610 6000);
DISPLAY 0.617021 (-7610 6000);
PAINT SKYBLUE (-7610 6000);
FORCEPROP 1 LAST PART_NUMBER G21796-026
J 0
(-7610 5950);
DISPLAY 0.617021 (-7610 5950);
PAINT BLUE (-7610 5950);
FORCEPROP 1 LAST PACK_TYPE 0402
J 0
(-7610 5900);
DISPLAY 0.617021 (-7610 5900);
PAINT SKYBLUE (-7610 5900);
FORCEPROP 2 LAST ROOM PROC_RSTS_PGOODS
J 0
(-7625 5825);
DISPLAY 1.617021 (-7625 5825);
PAINT WHITE (-7625 5825);
DISPLAY INVISIBLE (-7625 5825);
FORCEPROP 2 LAST $SEC 1
J 0
(-7600 6275);
DISPLAY 1.510638 (-7600 6275);
PAINT MONO (-7600 6275);
DISPLAY INVISIBLE (-7600 6275);
FORCEPROP 2 LAST CDS_SEC 1
J 0
(-7600 6275);
DISPLAY 2.276596 (-7600 6275);
PAINT ORANGE (-7600 6275);
DISPLAY INVISIBLE (-7600 6275);
FORCEPROP 2 LAST CDS_LIB mstr_discrete
J 0
(-7650 6050);
DISPLAY 1.617021 (-7650 6050);
PAINT ORANGE (-7650 6050);
DISPLAY INVISIBLE (-7650 6050);
FORCEPROP 2 LAST BOM_COST PROC_SIDEBAND
J 0
(-7650 6050);
DISPLAY 1.617021 (-7650 6050);
PAINT WHITE (-7650 6050);
DISPLAY INVISIBLE (-7650 6050);
FORCEPROP 2 LAST CDS_LOCATION R25W177
J 0
(-7605 6175);
DISPLAY 0.617021 (-7605 6175);
PAINT AQUA (-7605 6175);
DISPLAY INVISIBLE (-7605 6175);
FORCEPROP 1 LAST PATH I18
J 0
(-7600 6225);
DISPLAY 0.978723 (-7600 6225);
PAINT WHITE (-7600 6225);
DISPLAY INVISIBLE (-7600 6225);
FORCEADD RES..2
(-7350 6050);
FORCEPROP 1 LASTPIN (-7350 5950) $PN 2
J 0
(-7345 5960);
DISPLAY 0.617021 (-7345 5960);
PAINT WHITE (-7345 5960);
FORCEPROP 1 LAST TOLERANCE 1%
J 0
(-7305 6100);
DISPLAY 0.617021 (-7305 6100);
PAINT SKYBLUE (-7305 6100);
FORCEPROP 1 LAST LOCATION R25W178
J 0
(-7305 6200);
DISPLAY 0.617021 (-7305 6200);
PAINT AQUA (-7305 6200);
FORCEPROP 1 LASTPIN (-7350 6150) $PN 1
J 0
(-7345 6112);
DISPLAY 0.617021 (-7345 6112);
PAINT WHITE (-7345 6112);
FORCEPROP 1 LAST MATERIAL CHIP
J 0
(-7310 6000);
DISPLAY 0.617021 (-7310 6000);
PAINT SKYBLUE (-7310 6000);
FORCEPROP 1 LAST WATTAGE 1/16W
J 0
(-7310 6050);
DISPLAY 0.617021 (-7310 6050);
PAINT SKYBLUE (-7310 6050);
FORCEPROP 1 LAST VALUE 1.00K
J 0
(-7305 6150);
DISPLAY 0.617021 (-7305 6150);
PAINT SKYBLUE (-7305 6150);
FORCEPROP 1 LAST PACK_TYPE 0402
J 0
(-7310 5900);
DISPLAY 0.617021 (-7310 5900);
PAINT SKYBLUE (-7310 5900);
FORCEPROP 1 LAST PART_NUMBER G21796-026
J 0
(-7310 5950);
DISPLAY 0.617021 (-7310 5950);
PAINT BLUE (-7310 5950);
FORCEPROP 2 LAST BOM_COST PROC_SIDEBAND
J 0
(-7350 6050);
DISPLAY 1.617021 (-7350 6050);
PAINT WHITE (-7350 6050);
DISPLAY INVISIBLE (-7350 6050);
FORCEPROP 2 LAST CDS_LIB mstr_discrete
J 0
(-7350 6050);
DISPLAY 1.617021 (-7350 6050);
PAINT ORANGE (-7350 6050);
DISPLAY INVISIBLE (-7350 6050);
FORCEPROP 2 LAST CDS_SEC 1
J 0
(-7300 6275);
DISPLAY 2.276596 (-7300 6275);
PAINT ORANGE (-7300 6275);
DISPLAY INVISIBLE (-7300 6275);
FORCEPROP 2 LAST $SEC 1
J 0
(-7300 6275);
DISPLAY 1.510638 (-7300 6275);
PAINT MONO (-7300 6275);
DISPLAY INVISIBLE (-7300 6275);
FORCEPROP 2 LAST ROOM PROC_RSTS_PGOODS
J 0
(-7325 5825);
DISPLAY 1.617021 (-7325 5825);
PAINT WHITE (-7325 5825);
DISPLAY INVISIBLE (-7325 5825);
FORCEPROP 2 LAST CDS_LOCATION R25W178
J 0
(-7305 6175);
DISPLAY 0.617021 (-7305 6175);
PAINT AQUA (-7305 6175);
DISPLAY INVISIBLE (-7305 6175);
FORCEPROP 1 LAST PATH I19
J 0
(-7300 6225);
DISPLAY 0.978723 (-7300 6225);
PAINT WHITE (-7300 6225);
DISPLAY INVISIBLE (-7300 6225);
FORCEADD RES..2
(-7050 6050);
FORCEPROP 1 LAST VALUE 1.00K
J 0
(-7005 6150);
DISPLAY 0.617021 (-7005 6150);
PAINT SKYBLUE (-7005 6150);
FORCEPROP 1 LAST MATERIAL CHIP
J 0
(-7010 6000);
DISPLAY 0.617021 (-7010 6000);
PAINT SKYBLUE (-7010 6000);
FORCEPROP 1 LAST PACK_TYPE 0402
J 0
(-7010 5900);
DISPLAY 0.617021 (-7010 5900);
PAINT SKYBLUE (-7010 5900);
FORCEPROP 1 LASTPIN (-7050 5950) $PN 2
J 0
(-7045 5960);
DISPLAY 0.617021 (-7045 5960);
PAINT WHITE (-7045 5960);
FORCEPROP 1 LAST LOCATION R25W160
J 0
(-7005 6200);
DISPLAY 0.617021 (-7005 6200);
PAINT AQUA (-7005 6200);
FORCEPROP 1 LAST PART_NUMBER G21796-026
J 0
(-7010 5950);
DISPLAY 0.617021 (-7010 5950);
PAINT BLUE (-7010 5950);
FORCEPROP 1 LASTPIN (-7050 6150) $PN 1
J 0
(-7045 6112);
DISPLAY 0.617021 (-7045 6112);
PAINT WHITE (-7045 6112);
FORCEPROP 1 LAST TOLERANCE 1%
J 0
(-7005 6100);
DISPLAY 0.617021 (-7005 6100);
PAINT SKYBLUE (-7005 6100);
FORCEPROP 1 LAST WATTAGE 1/16W
J 0
(-7010 6050);
DISPLAY 0.617021 (-7010 6050);
PAINT SKYBLUE (-7010 6050);
FORCEPROP 2 LAST ROOM PROC_RSTS_PGOODS
J 0
(-7025 5825);
DISPLAY 1.617021 (-7025 5825);
PAINT WHITE (-7025 5825);
DISPLAY INVISIBLE (-7025 5825);
FORCEPROP 2 LAST $SEC 1
J 0
(-7000 6275);
DISPLAY 1.510638 (-7000 6275);
PAINT MONO (-7000 6275);
DISPLAY INVISIBLE (-7000 6275);
FORCEPROP 2 LAST CDS_SEC 1
J 0
(-7000 6275);
DISPLAY 2.276596 (-7000 6275);
PAINT ORANGE (-7000 6275);
DISPLAY INVISIBLE (-7000 6275);
FORCEPROP 2 LAST CDS_LIB mstr_discrete
J 0
(-7050 6050);
DISPLAY 1.617021 (-7050 6050);
PAINT ORANGE (-7050 6050);
DISPLAY INVISIBLE (-7050 6050);
FORCEPROP 2 LAST BOM_COST PROC_SIDEBAND
J 0
(-7050 6050);
DISPLAY 1.617021 (-7050 6050);
PAINT WHITE (-7050 6050);
DISPLAY INVISIBLE (-7050 6050);
FORCEPROP 2 LAST CDS_LOCATION R25W160
J 0
(-7005 6175);
DISPLAY 0.617021 (-7005 6175);
PAINT AQUA (-7005 6175);
DISPLAY INVISIBLE (-7005 6175);
FORCEPROP 1 LAST PATH I20
J 0
(-7000 6225);
DISPLAY 0.978723 (-7000 6225);
PAINT WHITE (-7000 6225);
DISPLAY INVISIBLE (-7000 6225);
FORCEADD RES..2
(-6750 6050);
FORCEPROP 1 LAST LOCATION R25W161
J 0
(-6705 6200);
DISPLAY 0.617021 (-6705 6200);
PAINT AQUA (-6705 6200);
FORCEPROP 1 LASTPIN (-6750 5950) $PN 2
J 0
(-6745 5960);
DISPLAY 0.617021 (-6745 5960);
PAINT WHITE (-6745 5960);
FORCEPROP 1 LASTPIN (-6750 6150) $PN 1
J 0
(-6745 6112);
DISPLAY 0.617021 (-6745 6112);
PAINT WHITE (-6745 6112);
FORCEPROP 1 LAST TOLERANCE 1%
J 0
(-6705 6100);
DISPLAY 0.617021 (-6705 6100);
PAINT SKYBLUE (-6705 6100);
FORCEPROP 1 LAST VALUE 1.00K
J 0
(-6705 6150);
DISPLAY 0.617021 (-6705 6150);
PAINT SKYBLUE (-6705 6150);
FORCEPROP 1 LAST MATERIAL CHIP
J 0
(-6710 6000);
DISPLAY 0.617021 (-6710 6000);
PAINT SKYBLUE (-6710 6000);
FORCEPROP 1 LAST WATTAGE 1/16W
J 0
(-6710 6050);
DISPLAY 0.617021 (-6710 6050);
PAINT SKYBLUE (-6710 6050);
FORCEPROP 1 LAST PART_NUMBER G21796-026
J 0
(-6710 5950);
DISPLAY 0.617021 (-6710 5950);
PAINT BLUE (-6710 5950);
FORCEPROP 1 LAST PACK_TYPE 0402
J 0
(-6710 5900);
DISPLAY 0.617021 (-6710 5900);
PAINT SKYBLUE (-6710 5900);
FORCEPROP 2 LAST CDS_LOCATION R25W161
J 0
(-6705 6175);
DISPLAY 0.617021 (-6705 6175);
PAINT AQUA (-6705 6175);
DISPLAY INVISIBLE (-6705 6175);
FORCEPROP 2 LAST BOM_COST PROC_SIDEBAND
J 0
(-6750 6050);
DISPLAY 1.617021 (-6750 6050);
PAINT WHITE (-6750 6050);
DISPLAY INVISIBLE (-6750 6050);
FORCEPROP 2 LAST CDS_LIB mstr_discrete
J 0
(-6750 6050);
DISPLAY 1.617021 (-6750 6050);
PAINT ORANGE (-6750 6050);
DISPLAY INVISIBLE (-6750 6050);
FORCEPROP 2 LAST CDS_SEC 1
J 0
(-6700 6275);
DISPLAY 2.276596 (-6700 6275);
PAINT ORANGE (-6700 6275);
DISPLAY INVISIBLE (-6700 6275);
FORCEPROP 2 LAST $SEC 1
J 0
(-6700 6275);
DISPLAY 1.510638 (-6700 6275);
PAINT MONO (-6700 6275);
DISPLAY INVISIBLE (-6700 6275);
FORCEPROP 2 LAST ROOM PROC_RSTS_PGOODS
J 0
(-6725 5825);
DISPLAY 1.617021 (-6725 5825);
PAINT WHITE (-6725 5825);
DISPLAY INVISIBLE (-6725 5825);
FORCEPROP 1 LAST PATH I21
J 0
(-6700 6225);
DISPLAY 0.978723 (-6700 6225);
PAINT WHITE (-6700 6225);
DISPLAY INVISIBLE (-6700 6225);
FORCEADD RES..2
(-6450 6050);
FORCEPROP 1 LAST LOCATION R25W158
J 0
(-6405 6200);
DISPLAY 0.617021 (-6405 6200);
PAINT AQUA (-6405 6200);
FORCEPROP 1 LASTPIN (-6450 5950) $PN 2
J 0
(-6445 5960);
DISPLAY 0.617021 (-6445 5960);
PAINT WHITE (-6445 5960);
FORCEPROP 1 LAST VALUE 1.00K
J 0
(-6405 6150);
DISPLAY 0.617021 (-6405 6150);
PAINT SKYBLUE (-6405 6150);
FORCEPROP 1 LASTPIN (-6450 6150) $PN 1
J 0
(-6445 6112);
DISPLAY 0.617021 (-6445 6112);
PAINT WHITE (-6445 6112);
FORCEPROP 1 LAST TOLERANCE 1%
J 0
(-6405 6100);
DISPLAY 0.617021 (-6405 6100);
PAINT SKYBLUE (-6405 6100);
FORCEPROP 1 LAST WATTAGE 1/16W
J 0
(-6410 6050);
DISPLAY 0.617021 (-6410 6050);
PAINT SKYBLUE (-6410 6050);
FORCEPROP 1 LAST MATERIAL CHIP
J 0
(-6410 6000);
DISPLAY 0.617021 (-6410 6000);
PAINT SKYBLUE (-6410 6000);
FORCEPROP 1 LAST PART_NUMBER G21796-026
J 0
(-6410 5950);
DISPLAY 0.617021 (-6410 5950);
PAINT BLUE (-6410 5950);
FORCEPROP 1 LAST PACK_TYPE 0402
J 0
(-6410 5900);
DISPLAY 0.617021 (-6410 5900);
PAINT SKYBLUE (-6410 5900);
FORCEPROP 2 LAST BOM_COST PROC_SIDEBAND
J 0
(-6450 6050);
DISPLAY 1.617021 (-6450 6050);
PAINT WHITE (-6450 6050);
DISPLAY INVISIBLE (-6450 6050);
FORCEPROP 2 LAST CDS_LIB mstr_discrete
J 0
(-6450 6050);
DISPLAY 1.617021 (-6450 6050);
PAINT ORANGE (-6450 6050);
DISPLAY INVISIBLE (-6450 6050);
FORCEPROP 2 LAST CDS_SEC 1
J 0
(-6400 6275);
DISPLAY 2.276596 (-6400 6275);
PAINT ORANGE (-6400 6275);
DISPLAY INVISIBLE (-6400 6275);
FORCEPROP 2 LAST $SEC 1
J 0
(-6400 6275);
DISPLAY 1.510638 (-6400 6275);
PAINT MONO (-6400 6275);
DISPLAY INVISIBLE (-6400 6275);
FORCEPROP 2 LAST ROOM PROC_RSTS_PGOODS
J 0
(-6425 5825);
DISPLAY 1.617021 (-6425 5825);
PAINT WHITE (-6425 5825);
DISPLAY INVISIBLE (-6425 5825);
FORCEPROP 2 LAST CDS_LOCATION R25W158
J 0
(-6405 6175);
DISPLAY 0.617021 (-6405 6175);
PAINT AQUA (-6405 6175);
DISPLAY INVISIBLE (-6405 6175);
FORCEPROP 1 LAST PATH I22
J 0
(-6400 6225);
DISPLAY 0.978723 (-6400 6225);
PAINT WHITE (-6400 6225);
DISPLAY INVISIBLE (-6400 6225);
FORCEADD GND..1
(-6200 5875);
FORCEPROP 3 LASTPIN (-6200 5925) SIG_NAME GND\g
J 0
(-6190 5935);
DISPLAY 0.659574 (-6190 5935);
PAINT MONO (-6190 5935);
DISPLAY INVISIBLE (-6190 5935);
FORCEPROP 2 LAST CDS_LIB mstr_symbols
J 0
(-6200 5875);
PAINT ORANGE (-6200 5875);
DISPLAY INVISIBLE (-6200 5875);
FORCEPROP 1 LAST SIZE 1B
J 0
(-6125 5825);
DISPLAY 1.893617 (-6125 5825);
PAINT GREEN (-6125 5825);
DISPLAY INVISIBLE (-6125 5825);
FORCEPROP 1 LAST VOLTAGE 0.0V
J 0
(-6245 5832);
DISPLAY 0.340426 (-6245 5832);
PAINT SKYBLUE (-6245 5832);
DISPLAY INVISIBLE (-6245 5832);
FORCEPROP 1 LAST PATH I23
J 0
(-6125 5875);
DISPLAY 0.872340 (-6125 5875);
PAINT AQUA (-6125 5875);
DISPLAY INVISIBLE (-6125 5875);
FORCEPROP 1 LAST BODY_TYPE PLUMBING
J 0
(-6245 5832);
DISPLAY 0.340426 (-6245 5832);
PAINT GREEN (-6245 5832);
DISPLAY INVISIBLE (-6245 5832);
FORCEPROP 1 LAST HDL_POWER GND
J 0
(-6200 6025);
DISPLAY 1.595745 (-6200 6025);
PAINT GREEN (-6200 6025);
DISPLAY INVISIBLE (-6200 6025);
FORCEADD RES..1
(-6050 6000);
FORCEPROP 1 LASTPIN (-5950 6000) $PN 2
J 0
(-5988 6012);
DISPLAY 0.617021 (-5988 6012);
PAINT ORANGE (-5988 6012);
FORCEPROP 1 LAST PACK_TYPE 0402
J 0
(-6150 5850);
DISPLAY 0.617021 (-6150 5850);
PAINT SKYBLUE (-6150 5850);
FORCEPROP 1 LAST TOLERANCE 1%
J 0
(-6150 5950);
DISPLAY 0.617021 (-6150 5950);
PAINT SKYBLUE (-6150 5950);
FORCEPROP 1 LASTPIN (-6150 6000) $PN 1
J 0
(-6138 6012);
DISPLAY 0.617021 (-6138 6012);
PAINT ORANGE (-6138 6012);
FORCEPROP 1 LAST LOCATION R25W159
J 0
(-6150 6150);
DISPLAY 0.617021 (-6150 6150);
PAINT AQUA (-6150 6150);
FORCEPROP 1 LAST VALUE 1.00K
J 0
(-6150 6050);
DISPLAY 0.617021 (-6150 6050);
PAINT SKYBLUE (-6150 6050);
FORCEPROP 1 LAST WATTAGE 1/16W
J 0
(-6150 5900);
DISPLAY 0.617021 (-6150 5900);
PAINT SKYBLUE (-6150 5900);
FORCEPROP 1 LAST PART_NUMBER G21796-026
J 0
(-6150 6100);
DISPLAY 0.617021 (-6150 6100);
PAINT BLUE (-6150 6100);
FORCEPROP 1 LAST MATERIAL CHIP
J 0
(-6150 5800);
DISPLAY 0.617021 (-6150 5800);
PAINT SKYBLUE (-6150 5800);
FORCEPROP 0 LAST CDS_SEC 1
J 0
(-6150 6200);
DISPLAY INVISIBLE (-6150 6200);
FORCEPROP 2 LAST ROOM PROC_RSTS_PGOODS
J 0
(-6100 6200);
DISPLAY 1.021277 (-6100 6200);
PAINT ORANGE (-6100 6200);
DISPLAY INVISIBLE (-6100 6200);
FORCEPROP 2 LAST SEC 1
J 0
(-6100 6200);
DISPLAY 0.680851 (-6100 6200);
PAINT MONO (-6100 6200);
DISPLAY INVISIBLE (-6100 6200);
FORCEPROP 2 LAST CDS_LIB mstr_discrete
J 0
(-6050 6000);
PAINT ORANGE (-6050 6000);
DISPLAY INVISIBLE (-6050 6000);
FORCEPROP 2 LAST SEC_TYPE 0402
J 0
(-6100 6200);
DISPLAY 1.021277 (-6100 6200);
PAINT ORANGE (-6100 6200);
DISPLAY INVISIBLE (-6100 6200);
FORCEPROP 0 LAST BOM_COST PROC_SIDEBAND
J 0
(-6100 6300);
DISPLAY 1.021277 (-6100 6300);
PAINT ORANGE (-6100 6300);
DISPLAY INVISIBLE (-6100 6300);
FORCEPROP 2 LAST CDS_LOCATION R25W159
J 0
(-6100 6050);
DISPLAY 0.617021 (-6100 6050);
PAINT AQUA (-6100 6050);
DISPLAY INVISIBLE (-6100 6050);
FORCEPROP 1 LAST PATH I24
J 0
(-6100 6150);
DISPLAY 0.978723 (-6100 6150);
PAINT WHITE (-6100 6150);
DISPLAY INVISIBLE (-6100 6150);
FORCEADD P3V3_STBY..1
(-7650 6350);
FORCEPROP 3 LASTPIN (-7650 6300) SIG_NAME P3V3_STBY\g
J 0
(-7640 6310);
DISPLAY 0.659574 (-7640 6310);
PAINT MONO (-7640 6310);
DISPLAY INVISIBLE (-7640 6310);
FORCEPROP 1 LAST VOLTAGE 3.3V
J 0
(-7695 6307);
DISPLAY 0.340426 (-7695 6307);
PAINT SKYBLUE (-7695 6307);
DISPLAY INVISIBLE (-7695 6307);
FORCEPROP 1 LAST SIZE 1B
J 0
(-7605 6372);
DISPLAY 0.340426 (-7605 6372);
PAINT GREEN (-7605 6372);
DISPLAY INVISIBLE (-7605 6372);
FORCEPROP 2 LAST CDS_LIB mstr_symbols
J 0
(-7650 6350);
PAINT ORANGE (-7650 6350);
DISPLAY INVISIBLE (-7650 6350);
FORCEPROP 1 LAST PATH I25
J 0
(-7605 6352);
DISPLAY 0.340426 (-7605 6352);
PAINT GREEN (-7605 6352);
DISPLAY INVISIBLE (-7605 6352);
FORCEPROP 1 LAST BODY_TYPE PLUMBING
J 0
(-7695 6307);
DISPLAY 0.340426 (-7695 6307);
PAINT GREEN (-7695 6307);
DISPLAY INVISIBLE (-7695 6307);
FORCEPROP 1 LAST HDL_POWER P3V3_STBY
J 0
(-7950 6225);
DISPLAY 0.872340 (-7950 6225);
PAINT ORANGE (-7950 6225);
DISPLAY INVISIBLE (-7950 6225);
FORCEADD CAP_A..1
(-5800 6050);
FORCEPROP 1 LASTPIN (-5800 5950) $PN 2
J 0
(-5790 5930);
DISPLAY 0.617021 (-5790 5930);
PAINT WHITE (-5790 5930);
FORCEPROP 1 LAST PACK_TYPE 0402V
J 0
(-5750 5900);
DISPLAY 0.617021 (-5750 5900);
PAINT SKYBLUE (-5750 5900);
FORCEPROP 1 LAST TOLERANCE 10%
J 0
(-5750 6050);
DISPLAY 0.617021 (-5750 6050);
PAINT SKYBLUE (-5750 6050);
FORCEPROP 1 LAST VOLTAGE 6.3V
J 0
(-5750 6100);
DISPLAY 0.617021 (-5750 6100);
PAINT SKYBLUE (-5750 6100);
FORCEPROP 1 LAST LOCATION C25W91
J 0
(-5750 6200);
DISPLAY 0.617021 (-5750 6200);
PAINT AQUA (-5750 6200);
FORCEPROP 1 LASTPIN (-5800 6150) $PN 1
J 0
(-5790 6130);
DISPLAY 0.617021 (-5790 6130);
PAINT WHITE (-5790 6130);
FORCEPROP 1 LAST VALUE 1.0UF
J 0
(-5750 6150);
DISPLAY 0.617021 (-5750 6150);
PAINT SKYBLUE (-5750 6150);
FORCEPROP 1 LAST PART_NUMBER D97712-004
J 0
(-5750 5950);
DISPLAY 0.617021 (-5750 5950);
PAINT BLUE (-5750 5950);
FORCEPROP 1 LAST MATERIAL X6S
J 0
(-5750 6000);
DISPLAY 0.617021 (-5750 6000);
PAINT SKYBLUE (-5750 6000);
FORCEPROP 2 LAST CDS_LOCATION C25W91
J 0
(-5750 6150);
DISPLAY 0.617021 (-5750 6150);
PAINT AQUA (-5750 6150);
DISPLAY INVISIBLE (-5750 6150);
FORCEPROP 2 LAST BOM_COST PROC_SIDEBAND
J 0
(-5800 6050);
DISPLAY 1.617021 (-5800 6050);
PAINT WHITE (-5800 6050);
DISPLAY INVISIBLE (-5800 6050);
FORCEPROP 2 LAST CDS_LIB dev_discrete
J 0
(-5800 6050);
PAINT ORANGE (-5800 6050);
DISPLAY INVISIBLE (-5800 6050);
FORCEPROP 2 LAST CDS_SEC 1
J 0
(-5750 6200);
PAINT ORANGE (-5750 6200);
DISPLAY INVISIBLE (-5750 6200);
FORCEPROP 2 LAST SEC_TYPE 0402V
J 0
(-5750 6250);
DISPLAY 1.617021 (-5750 6250);
PAINT MONO (-5750 6250);
DISPLAY INVISIBLE (-5750 6250);
FORCEPROP 2 LAST SEC 1
J 0
(-5750 6250);
DISPLAY 1.510638 (-5750 6250);
PAINT MONO (-5750 6250);
DISPLAY INVISIBLE (-5750 6250);
FORCEPROP 2 LAST ROOM PROC_RSTS_PGOODS
J 0
(-5750 5800);
DISPLAY 1.617021 (-5750 5800);
PAINT WHITE (-5750 5800);
DISPLAY INVISIBLE (-5750 5800);
FORCEPROP 1 LAST PATH I26
J 0
(-5750 6200);
DISPLAY 0.978723 (-5750 6200);
PAINT WHITE (-5750 6200);
DISPLAY INVISIBLE (-5750 6200);
FORCEADD GND..1
(-5800 5875);
FORCEPROP 3 LASTPIN (-5800 5925) SIG_NAME GND\g
J 0
(-5790 5935);
DISPLAY 0.659574 (-5790 5935);
PAINT MONO (-5790 5935);
DISPLAY INVISIBLE (-5790 5935);
FORCEPROP 1 LAST SIZE 1B
J 0
(-5725 5825);
DISPLAY 1.893617 (-5725 5825);
PAINT GREEN (-5725 5825);
DISPLAY INVISIBLE (-5725 5825);
FORCEPROP 2 LAST CDS_LIB mstr_symbols
J 0
(-5800 5875);
DISPLAY 2.212766 (-5800 5875);
PAINT ORANGE (-5800 5875);
DISPLAY INVISIBLE (-5800 5875);
FORCEPROP 1 LAST VOLTAGE 0.0V
J 0
(-5845 5832);
DISPLAY 0.340426 (-5845 5832);
PAINT SKYBLUE (-5845 5832);
DISPLAY INVISIBLE (-5845 5832);
FORCEPROP 1 LAST PATH I27
J 0
(-5725 5875);
DISPLAY 0.872340 (-5725 5875);
PAINT AQUA (-5725 5875);
DISPLAY INVISIBLE (-5725 5875);
FORCEPROP 1 LAST BODY_TYPE PLUMBING
J 0
(-5845 5832);
DISPLAY 0.340426 (-5845 5832);
PAINT GREEN (-5845 5832);
DISPLAY INVISIBLE (-5845 5832);
FORCEPROP 1 LAST HDL_POWER GND
J 0
(-5800 6025);
DISPLAY 1.595745 (-5800 6025);
PAINT GREEN (-5800 6025);
DISPLAY INVISIBLE (-5800 6025);
FORCEADD P1V05_PCH_STBY..1
(-4000 4350);
FORCEPROP 3 LASTPIN (-4000 4300) SIG_NAME P1V05_PCH_STBY\g
J 0
(-3990 4310);
DISPLAY 0.659574 (-3990 4310);
PAINT MONO (-3990 4310);
DISPLAY INVISIBLE (-3990 4310);
FORCEPROP 2 LAST CDS_LIB mstr_symbols
J 0
(-4000 4350);
PAINT ORANGE (-4000 4350);
DISPLAY INVISIBLE (-4000 4350);
FORCEPROP 1 LAST VOLTAGE 1.05V
J 0
(-4045 4307);
DISPLAY 0.340426 (-4045 4307);
PAINT SKYBLUE (-4045 4307);
DISPLAY INVISIBLE (-4045 4307);
FORCEPROP 1 LAST PATH I28
J 0
(-3950 4375);
DISPLAY 0.872340 (-3950 4375);
PAINT AQUA (-3950 4375);
DISPLAY INVISIBLE (-3950 4375);
FORCEPROP 1 LAST BODY_TYPE PLUMBING
J 0
(-4045 4307);
DISPLAY 0.340426 (-4045 4307);
PAINT GREEN (-4045 4307);
DISPLAY INVISIBLE (-4045 4307);
FORCEPROP 1 LAST HDL_POWER P1V05_PCH_STBY
J 0
(-4000 4400);
DISPLAY 0.872340 (-4000 4400);
PAINT GREEN (-4000 4400);
DISPLAY INVISIBLE (-4000 4400);
FORCEADD GND..1
(-4400 5025);
FORCEPROP 3 LASTPIN (-4400 5075) SIG_NAME GND\g
J 0
(-4390 5085);
DISPLAY 0.659574 (-4390 5085);
PAINT MONO (-4390 5085);
DISPLAY INVISIBLE (-4390 5085);
FORCEPROP 2 LAST CDS_LIB mstr_symbols
J 0
(-4400 5025);
PAINT ORANGE (-4400 5025);
DISPLAY INVISIBLE (-4400 5025);
FORCEPROP 1 LAST SIZE 1B
J 0
(-4325 4975);
DISPLAY 1.893617 (-4325 4975);
PAINT GREEN (-4325 4975);
DISPLAY INVISIBLE (-4325 4975);
FORCEPROP 1 LAST VOLTAGE 0.0V
J 0
(-4445 4982);
DISPLAY 0.340426 (-4445 4982);
PAINT SKYBLUE (-4445 4982);
DISPLAY INVISIBLE (-4445 4982);
FORCEPROP 1 LAST PATH I29
J 0
(-4325 5025);
DISPLAY 0.872340 (-4325 5025);
PAINT AQUA (-4325 5025);
DISPLAY INVISIBLE (-4325 5025);
FORCEPROP 1 LAST BODY_TYPE PLUMBING
J 0
(-4445 4982);
DISPLAY 0.340426 (-4445 4982);
PAINT GREEN (-4445 4982);
DISPLAY INVISIBLE (-4445 4982);
FORCEPROP 1 LAST HDL_POWER GND
J 0
(-4400 5175);
DISPLAY 1.595745 (-4400 5175);
PAINT GREEN (-4400 5175);
DISPLAY INVISIBLE (-4400 5175);
FORCEADD GND..1
(-3050 2825);
FORCEPROP 3 LASTPIN (-3050 2875) SIG_NAME GND\g
J 0
(-3040 2885);
DISPLAY 0.659574 (-3040 2885);
PAINT MONO (-3040 2885);
DISPLAY INVISIBLE (-3040 2885);
FORCEPROP 1 LAST SIZE 1B
J 0
(-2975 2775);
DISPLAY 2.382979 (-2975 2775);
PAINT GREEN (-2975 2775);
DISPLAY INVISIBLE (-2975 2775);
FORCEPROP 2 LAST CDS_LIB mstr_symbols
J 0
(-3050 2825);
PAINT MONO (-3050 2825);
DISPLAY INVISIBLE (-3050 2825);
FORCEPROP 1 LAST VOLTAGE 0.0V
J 0
(-3095 2782);
DISPLAY 0.340426 (-3095 2782);
PAINT SKYBLUE (-3095 2782);
DISPLAY INVISIBLE (-3095 2782);
FORCEPROP 1 LAST PATH I31
J 0
(-2975 2825);
DISPLAY 0.872340 (-2975 2825);
PAINT AQUA (-2975 2825);
DISPLAY INVISIBLE (-2975 2825);
FORCEPROP 1 LAST BODY_TYPE PLUMBING
J 0
(-3095 2782);
DISPLAY 0.340426 (-3095 2782);
PAINT GREEN (-3095 2782);
DISPLAY INVISIBLE (-3095 2782);
FORCEPROP 1 LAST HDL_POWER GND
J 0
(-3050 2975);
PAINT GREEN (-3050 2975);
DISPLAY INVISIBLE (-3050 2975);
FORCEADD CAP..1
(-3050 3000);
FORCEPROP 1 LAST TOLERANCE 10%
J 0
(-3000 2950);
DISPLAY 0.617021 (-3000 2950);
PAINT SKYBLUE (-3000 2950);
FORCEPROP 1 LASTPIN (-3050 2900) $PN 2
J 0
(-3040 2880);
DISPLAY 0.617021 (-3040 2880);
PAINT ORANGE (-3040 2880);
FORCEPROP 1 LAST PACK_TYPE 0402
J 0
(-3000 2800);
DISPLAY 0.617021 (-3000 2800);
PAINT SKYBLUE (-3000 2800);
FORCEPROP 1 LAST VALUE 1.0UF
J 0
(-3000 3050);
DISPLAY 0.617021 (-3000 3050);
PAINT SKYBLUE (-3000 3050);
FORCEPROP 1 LASTPIN (-3050 3100) $PN 1
J 0
(-3040 3080);
DISPLAY 0.617021 (-3040 3080);
PAINT ORANGE (-3040 3080);
FORCEPROP 1 LAST VOLTAGE 16V
J 0
(-3000 3000);
DISPLAY 0.617021 (-3000 3000);
PAINT SKYBLUE (-3000 3000);
FORCEPROP 1 LAST LOCATION C25W94
J 0
(-3000 3100);
DISPLAY 0.617021 (-3000 3100);
PAINT AQUA (-3000 3100);
FORCEPROP 1 LAST MATERIAL X6S
J 0
(-3000 2900);
DISPLAY 0.617021 (-3000 2900);
PAINT SKYBLUE (-3000 2900);
FORCEPROP 1 LAST PART_NUMBER D97712-011
J 0
(-3000 2850);
DISPLAY 0.617021 (-3000 2850);
PAINT BLUE (-3000 2850);
FORCEPROP 0 LAST ROOM DEBUG
J 0
(-3000 3200);
DISPLAY 1.021277 (-3000 3200);
PAINT ORANGE (-3000 3200);
DISPLAY INVISIBLE (-3000 3200);
FORCEPROP 2 LAST SEC 1
J 0
(-3000 3200);
DISPLAY 0.680851 (-3000 3200);
PAINT MONO (-3000 3200);
DISPLAY INVISIBLE (-3000 3200);
FORCEPROP 2 LAST SEC_TYPE 0402
J 0
(-3000 3200);
DISPLAY 1.021277 (-3000 3200);
PAINT ORANGE (-3000 3200);
DISPLAY INVISIBLE (-3000 3200);
FORCEPROP 2 LAST CDS_LIB mstr_discrete
J 0
(-3050 3000);
PAINT MONO (-3050 3000);
DISPLAY INVISIBLE (-3050 3000);
FORCEPROP 2 LAST CDS_LOCATION C25W94
J 0
(-3000 3100);
DISPLAY 0.617021 (-3000 3100);
PAINT AQUA (-3000 3100);
DISPLAY INVISIBLE (-3000 3100);
FORCEPROP 0 LAST CDS_SEC 1
J 0
(-3000 3150);
DISPLAY INVISIBLE (-3000 3150);
FORCEPROP 1 LAST PATH I32
J 0
(-3000 3150);
DISPLAY 0.978723 (-3000 3150);
PAINT WHITE (-3000 3150);
DISPLAY INVISIBLE (-3000 3150);
FORCEADD TTL3126..3
(-3700 3750);
FORCEPROP 1 LAST PART_NUMBER D18317-001
J 0
(-3850 3275);
DISPLAY 0.617021 (-3850 3275);
PAINT BLUE (-3850 3275);
FORCEPROP 2 LASTPIN (-3900 3800) $PN 10
J 2
(-3910 3810);
DISPLAY 0.617021 (-3910 3810);
PAINT WHITE (-3910 3810);
FORCEPROP 2 LASTPIN (-3500 4100) $PN 11
J 0
(-3490 4110);
DISPLAY 0.617021 (-3490 4110);
PAINT WHITE (-3490 4110);
FORCEPROP 1 LAST POWER_GROUP VCC=P3V3_STBY;GND=GND
J 0
(-3850 3225);
DISPLAY 0.617021 (-3850 3225);
PAINT ORANGE (-3850 3225);
FORCEPROP 2 LASTPIN (-3500 3500) $PN 3
J 0
(-3490 3510);
DISPLAY 0.617021 (-3490 3510);
PAINT WHITE (-3490 3510);
FORCEPROP 1 LAST LOCATION U25W12
J 0
(-3850 4325);
DISPLAY 0.617021 (-3850 4325);
PAINT AQUA (-3850 4325);
FORCEPROP 2 LASTPIN (-3500 3900) $PN 8
J 0
(-3490 3910);
DISPLAY 0.617021 (-3490 3910);
PAINT WHITE (-3490 3910);
FORCEPROP 2 LASTPIN (-3900 4000) $PN 13
J 2
(-3910 4010);
DISPLAY 0.617021 (-3910 4010);
PAINT WHITE (-3910 4010);
FORCEPROP 2 LASTPIN (-3900 3900) $PN 9
J 2
(-3910 3910);
DISPLAY 0.617021 (-3910 3910);
PAINT WHITE (-3910 3910);
FORCEPROP 2 LASTPIN (-3500 3700) $PN 6
J 0
(-3490 3710);
DISPLAY 0.617021 (-3490 3710);
PAINT WHITE (-3490 3710);
FORCEPROP 1 LAST MATERIAL IC
J 0
(-3850 4275);
DISPLAY 0.617021 (-3850 4275);
PAINT SKYBLUE (-3850 4275);
FORCEPROP 2 LASTPIN (-3900 3400) $PN 1
J 2
(-3910 3410);
DISPLAY 0.617021 (-3910 3410);
PAINT WHITE (-3910 3410);
FORCEPROP 2 LASTPIN (-3900 4100) $PN 12
J 2
(-3910 4110);
DISPLAY 0.617021 (-3910 4110);
PAINT WHITE (-3910 4110);
FORCEPROP 2 LASTPIN (-3900 3600) $PN 4
J 2
(-3910 3610);
DISPLAY 0.617021 (-3910 3610);
PAINT WHITE (-3910 3610);
FORCEPROP 2 LASTPIN (-3900 3500) $PN 2
J 2
(-3910 3510);
DISPLAY 0.617021 (-3910 3510);
PAINT WHITE (-3910 3510);
FORCEPROP 2 LASTPIN (-3900 3700) $PN 5
J 2
(-3910 3710);
DISPLAY 0.617021 (-3910 3710);
PAINT WHITE (-3910 3710);
FORCEPROP 1 LAST VALUE 74CBTLV3126
J 0
(-3850 4225);
DISPLAY 0.617021 (-3850 4225);
PAINT SKYBLUE (-3850 4225);
FORCEPROP 1 LAST PACK_TYPE QFNLF
J 0
(-3850 4375);
DISPLAY 1.595745 (-3850 4375);
PAINT SKYBLUE (-3850 4375);
DISPLAY INVISIBLE (-3850 4375);
FORCEPROP 1 LAST HAS_FIXED_SIZE 4B
J 0
(-3850 3175);
DISPLAY 1.595745 (-3850 3175);
PAINT BLUE (-3850 3175);
DISPLAY INVISIBLE (-3850 3175);
FORCEPROP 2 LAST CDS_LIB mstr_ttl
J 0
(-3700 3750);
PAINT ORANGE (-3700 3750);
DISPLAY INVISIBLE (-3700 3750);
FORCEPROP 0 LAST ROOM DEBUG
J 0
(-3850 4425);
DISPLAY 1.021277 (-3850 4425);
PAINT ORANGE (-3850 4425);
DISPLAY INVISIBLE (-3850 4425);
FORCEPROP 2 LAST CDS_LOCATION U25W12
J 0
(-3850 4325);
DISPLAY 0.617021 (-3850 4325);
PAINT AQUA (-3850 4325);
DISPLAY INVISIBLE (-3850 4325);
FORCEPROP 0 LASTPIN (-3500 4100) CDS_SEC 4
J 0
(-3490 4157);
DISPLAY 0.808511 (-3490 4157);
DISPLAY INVISIBLE (-3490 4157);
FORCEPROP 0 LASTPIN (-3500 4100) $SEC 4
J 0
(-3490 4110);
DISPLAY 0.808511 (-3490 4110);
DISPLAY INVISIBLE (-3490 4110);
FORCEPROP 0 LASTPIN (-3500 3900) CDS_SEC 3
J 0
(-3490 3957);
DISPLAY 0.808511 (-3490 3957);
DISPLAY INVISIBLE (-3490 3957);
FORCEPROP 0 LASTPIN (-3500 3900) $SEC 3
J 0
(-3490 3910);
DISPLAY 0.808511 (-3490 3910);
DISPLAY INVISIBLE (-3490 3910);
FORCEPROP 0 LASTPIN (-3500 3700) CDS_SEC 2
J 0
(-3490 3757);
DISPLAY 0.808511 (-3490 3757);
DISPLAY INVISIBLE (-3490 3757);
FORCEPROP 0 LASTPIN (-3500 3700) $SEC 2
J 0
(-3490 3710);
DISPLAY 0.808511 (-3490 3710);
DISPLAY INVISIBLE (-3490 3710);
FORCEPROP 0 LASTPIN (-3500 3500) CDS_SEC 1
J 0
(-3490 3557);
DISPLAY 0.808511 (-3490 3557);
DISPLAY INVISIBLE (-3490 3557);
FORCEPROP 0 LASTPIN (-3500 3500) $SEC 1
J 0
(-3490 3510);
DISPLAY 0.808511 (-3490 3510);
DISPLAY INVISIBLE (-3490 3510);
FORCEPROP 0 LASTPIN (-3900 3900) CDS_SEC 3
J 2
(-3910 3957);
DISPLAY 0.808511 (-3910 3957);
DISPLAY INVISIBLE (-3910 3957);
FORCEPROP 0 LASTPIN (-3900 3900) $SEC 3
J 2
(-3910 3910);
DISPLAY 0.808511 (-3910 3910);
DISPLAY INVISIBLE (-3910 3910);
FORCEPROP 0 LASTPIN (-3900 4100) CDS_SEC 4
J 2
(-3910 4157);
DISPLAY 0.808511 (-3910 4157);
DISPLAY INVISIBLE (-3910 4157);
FORCEPROP 0 LASTPIN (-3900 4100) $SEC 4
J 2
(-3910 4110);
DISPLAY 0.808511 (-3910 4110);
DISPLAY INVISIBLE (-3910 4110);
FORCEPROP 0 LASTPIN (-3900 3700) CDS_SEC 2
J 2
(-3910 3757);
DISPLAY 0.808511 (-3910 3757);
DISPLAY INVISIBLE (-3910 3757);
FORCEPROP 0 LASTPIN (-3900 3700) $SEC 2
J 2
(-3910 3710);
DISPLAY 0.808511 (-3910 3710);
DISPLAY INVISIBLE (-3910 3710);
FORCEPROP 0 LASTPIN (-3900 3500) CDS_SEC 1
J 2
(-3910 3557);
DISPLAY 0.808511 (-3910 3557);
DISPLAY INVISIBLE (-3910 3557);
FORCEPROP 0 LASTPIN (-3900 3500) $SEC 1
J 2
(-3910 3510);
DISPLAY 0.808511 (-3910 3510);
DISPLAY INVISIBLE (-3910 3510);
FORCEPROP 0 LASTPIN (-3900 4000) CDS_SEC 4
J 2
(-3910 4057);
DISPLAY 0.808511 (-3910 4057);
DISPLAY INVISIBLE (-3910 4057);
FORCEPROP 0 LASTPIN (-3900 4000) $SEC 4
J 2
(-3910 4010);
DISPLAY 0.808511 (-3910 4010);
DISPLAY INVISIBLE (-3910 4010);
FORCEPROP 0 LASTPIN (-3900 3800) CDS_SEC 3
J 2
(-3910 3857);
DISPLAY 0.808511 (-3910 3857);
DISPLAY INVISIBLE (-3910 3857);
FORCEPROP 0 LASTPIN (-3900 3800) $SEC 3
J 2
(-3910 3810);
DISPLAY 0.808511 (-3910 3810);
DISPLAY INVISIBLE (-3910 3810);
FORCEPROP 0 LASTPIN (-3900 3600) CDS_SEC 2
J 2
(-3910 3657);
DISPLAY 0.808511 (-3910 3657);
DISPLAY INVISIBLE (-3910 3657);
FORCEPROP 0 LASTPIN (-3900 3600) $SEC 2
J 2
(-3910 3610);
DISPLAY 0.808511 (-3910 3610);
DISPLAY INVISIBLE (-3910 3610);
FORCEPROP 0 LASTPIN (-3900 3400) CDS_SEC 1
J 2
(-3910 3457);
DISPLAY 0.808511 (-3910 3457);
DISPLAY INVISIBLE (-3910 3457);
FORCEPROP 0 LASTPIN (-3900 3400) $SEC 1
J 2
(-3910 3410);
DISPLAY 0.808511 (-3910 3410);
DISPLAY INVISIBLE (-3910 3410);
FORCEPROP 1 LAST PATH I33
J 0
(-3400 4275);
DISPLAY 0.978723 (-3400 4275);
PAINT BLUE (-3400 4275);
DISPLAY INVISIBLE (-3400 4275);
FORCEADD OFFPAGE..2
(-2100 3700);
FORCEPROP 2 LAST $XR3 112 
J 0
(-1611 3700);
DISPLAY 0.638298 (-1611 3700);
PAINT MONO (-1611 3700);
FORCEPROP 2 LAST $XR2 55 
J 0
(-1701 3700);
DISPLAY 0.638298 (-1701 3700);
PAINT MONO (-1701 3700);
FORCEPROP 2 LAST $XR1 21 
J 0
(-1791 3700);
DISPLAY 0.638298 (-1791 3700);
PAINT MONO (-1791 3700);
FORCEPROP 2 LAST $XR0 111 
J 0
(-1911 3700);
DISPLAY 0.638298 (-1911 3700);
PAINT MONO (-1911 3700);
FORCEPROP 2 LAST CDS_LIB mstr_standard
J 0
(-2100 3700);
DISPLAY 2.212766 (-2100 3700);
PAINT ORANGE (-2100 3700);
DISPLAY INVISIBLE (-2100 3700);
FORCEPROP 2 LAST BOM_COST DEBUG
J 0
(-1900 3750);
DISPLAY 1.617021 (-1900 3750);
PAINT WHITE (-1900 3750);
DISPLAY INVISIBLE (-1900 3750);
FORCEPROP 2 LAST ROOM CPU_XDP_DEBUG
J 0
(-1900 3750);
DISPLAY 1.617021 (-1900 3750);
PAINT WHITE (-1900 3750);
DISPLAY INVISIBLE (-1900 3750);
FORCEPROP 2 LAST PATH I39
J 0
(-1600 3750);
DISPLAY 1.021277 (-1600 3750);
PAINT ORANGE (-1600 3750);
DISPLAY INVISIBLE (-1600 3750);
FORCEPROP 1 LAST OFFPAGE TRUE
J 0
(-1775 3575);
PAINT GREEN (-1775 3575);
DISPLAY INVISIBLE (-1775 3575);
FORCEPROP 1 LAST COMMENT_BODY TRUE
J 0
(-2145 3605);
DISPLAY 1.893617 (-2145 3605);
PAINT PEACH (-2145 3605);
DISPLAY INVISIBLE (-2145 3605);
FORCEADD RES..2
(-6400 3850);
FORCEPROP 1 LAST PART_NUMBER G21796-016
R 1
J 0
(-6335 3725);
DISPLAY 0.617021 (-6335 3725);
PAINT BLUE (-6335 3725);
FORCEPROP 1 LAST WATTAGE 1/16W
J 0
(-6310 3800);
DISPLAY 0.617021 (-6310 3800);
PAINT SKYBLUE (-6310 3800);
FORCEPROP 1 LAST MATERIAL CHIP
J 0
(-6310 3750);
DISPLAY 0.617021 (-6310 3750);
PAINT SKYBLUE (-6310 3750);
FORCEPROP 1 LAST TOLERANCE 1%
J 0
(-6305 3850);
DISPLAY 0.617021 (-6305 3850);
PAINT SKYBLUE (-6305 3850);
FORCEPROP 1 LAST LOCATION R25W174
J 0
(-6305 3950);
DISPLAY 0.617021 (-6305 3950);
PAINT AQUA (-6305 3950);
FORCEPROP 1 LAST VALUE 10.0K
J 0
(-6305 3900);
DISPLAY 0.617021 (-6305 3900);
PAINT SKYBLUE (-6305 3900);
FORCEPROP 1 LASTPIN (-6400 3950) $PN 1
J 0
(-6395 3912);
DISPLAY 0.617021 (-6395 3912);
PAINT ORANGE (-6395 3912);
FORCEPROP 1 LASTPIN (-6400 3750) $PN 2
J 0
(-6395 3760);
DISPLAY 0.617021 (-6395 3760);
PAINT ORANGE (-6395 3760);
FORCEPROP 1 LAST PACK_TYPE 0402
J 0
(-6310 3700);
DISPLAY 0.617021 (-6310 3700);
PAINT SKYBLUE (-6310 3700);
FORCEPROP 2 LAST SEC_TYPE 0402
J 0
(-6350 4075);
DISPLAY 1.021277 (-6350 4075);
PAINT ORANGE (-6350 4075);
DISPLAY INVISIBLE (-6350 4075);
FORCEPROP 2 LAST SEC 1
J 0
(-6350 4075);
DISPLAY 0.680851 (-6350 4075);
PAINT MONO (-6350 4075);
DISPLAY INVISIBLE (-6350 4075);
FORCEPROP 2 LAST BOM_COST PROC_SIDEBAND
J 0
(-6400 3850);
PAINT WHITE (-6400 3850);
DISPLAY INVISIBLE (-6400 3850);
FORCEPROP 2 LAST CDS_LIB mstr_discrete
J 2
(-6400 3850);
PAINT ORANGE (-6400 3850);
DISPLAY INVISIBLE (-6400 3850);
FORCEPROP 2 LAST ROOM CPU0
J 0
(-6375 3625);
PAINT WHITE (-6375 3625);
DISPLAY INVISIBLE (-6375 3625);
FORCEPROP 2 LAST CDS_LOCATION R25W174
J 0
(-6355 3975);
DISPLAY 0.617021 (-6355 3975);
PAINT AQUA (-6355 3975);
DISPLAY INVISIBLE (-6355 3975);
FORCEPROP 0 LAST CDS_SEC 1
J 0
(-6300 4000);
DISPLAY INVISIBLE (-6300 4000);
FORCEPROP 1 LAST PATH I4
J 0
(-6350 4025);
DISPLAY 0.978723 (-6350 4025);
PAINT WHITE (-6350 4025);
DISPLAY INVISIBLE (-6350 4025);
FORCEADD OFFPAGE..2
(-2100 3900);
FORCEPROP 2 LAST $XR2 118 
J 0
(-1671 3900);
DISPLAY 0.638298 (-1671 3900);
PAINT MONO (-1671 3900);
FORCEPROP 2 LAST $XR1 112 
J 0
(-1791 3900);
DISPLAY 0.638298 (-1791 3900);
PAINT MONO (-1791 3900);
FORCEPROP 2 LAST $XR0 111 
J 0
(-1911 3900);
DISPLAY 0.638298 (-1911 3900);
PAINT MONO (-1911 3900);
FORCEPROP 2 LAST PATH I40
J 0
(-1650 3950);
DISPLAY 1.021277 (-1650 3950);
PAINT ORANGE (-1650 3950);
DISPLAY INVISIBLE (-1650 3950);
FORCEPROP 2 LAST CDS_LIB mstr_standard
J 0
(-2100 3900);
DISPLAY 2.212766 (-2100 3900);
PAINT ORANGE (-2100 3900);
DISPLAY INVISIBLE (-2100 3900);
FORCEPROP 2 LAST BOM_COST DEBUG
J 0
(-1900 3950);
DISPLAY 1.617021 (-1900 3950);
PAINT WHITE (-1900 3950);
DISPLAY INVISIBLE (-1900 3950);
FORCEPROP 2 LAST ROOM CPU_XDP_DEBUG
J 0
(-1900 3950);
DISPLAY 1.617021 (-1900 3950);
PAINT WHITE (-1900 3950);
DISPLAY INVISIBLE (-1900 3950);
FORCEPROP 1 LAST OFFPAGE TRUE
J 0
(-1775 3775);
PAINT GREEN (-1775 3775);
DISPLAY INVISIBLE (-1775 3775);
FORCEPROP 1 LAST COMMENT_BODY TRUE
J 0
(-2145 3805);
DISPLAY 1.893617 (-2145 3805);
PAINT PEACH (-2145 3805);
DISPLAY INVISIBLE (-2145 3805);
FORCEADD OFFPAGE..2
(-2100 4100);
FORCEPROP 2 LAST $XR2 112 
J 0
(-1671 4100);
DISPLAY 0.638298 (-1671 4100);
PAINT MONO (-1671 4100);
FORCEPROP 2 LAST $XR1 118 
J 0
(-1791 4100);
DISPLAY 0.638298 (-1791 4100);
PAINT MONO (-1791 4100);
FORCEPROP 2 LAST $XR0 111 
J 0
(-1911 4100);
DISPLAY 0.638298 (-1911 4100);
PAINT MONO (-1911 4100);
FORCEPROP 2 LAST PATH I41
J 0
(-1650 4150);
DISPLAY 1.021277 (-1650 4150);
PAINT ORANGE (-1650 4150);
DISPLAY INVISIBLE (-1650 4150);
FORCEPROP 2 LAST ROOM CPU_XDP_DEBUG
J 0
(-1900 4150);
DISPLAY 1.617021 (-1900 4150);
PAINT WHITE (-1900 4150);
DISPLAY INVISIBLE (-1900 4150);
FORCEPROP 2 LAST BOM_COST DEBUG
J 0
(-1900 4150);
DISPLAY 1.617021 (-1900 4150);
PAINT WHITE (-1900 4150);
DISPLAY INVISIBLE (-1900 4150);
FORCEPROP 2 LAST CDS_LIB mstr_standard
J 0
(-2100 4100);
DISPLAY 2.212766 (-2100 4100);
PAINT ORANGE (-2100 4100);
DISPLAY INVISIBLE (-2100 4100);
FORCEPROP 1 LAST OFFPAGE TRUE
J 0
(-1775 3975);
PAINT GREEN (-1775 3975);
DISPLAY INVISIBLE (-1775 3975);
FORCEPROP 1 LAST COMMENT_BODY TRUE
J 0
(-2145 4005);
DISPLAY 1.893617 (-2145 4005);
PAINT PEACH (-2145 4005);
DISPLAY INVISIBLE (-2145 4005);
FORCEADD OFFPAGE..2
(-2600 5350);
FORCEPROP 2 LAST $XR2 112 
J 0
(-2171 5350);
DISPLAY 0.638298 (-2171 5350);
PAINT MONO (-2171 5350);
FORCEPROP 2 LAST $XR1 118 
J 0
(-2291 5350);
DISPLAY 0.638298 (-2291 5350);
PAINT MONO (-2291 5350);
FORCEPROP 2 LAST $XR0 111 
J 0
(-2411 5350);
DISPLAY 0.638298 (-2411 5350);
PAINT MONO (-2411 5350);
FORCEPROP 2 LAST PATH I45
J 0
(-2150 5400);
DISPLAY 1.021277 (-2150 5400);
PAINT ORANGE (-2150 5400);
DISPLAY INVISIBLE (-2150 5400);
FORCEPROP 2 LAST CDS_LIB mstr_standard
J 0
(-2600 5350);
DISPLAY 2.212766 (-2600 5350);
PAINT ORANGE (-2600 5350);
DISPLAY INVISIBLE (-2600 5350);
FORCEPROP 2 LAST BOM_COST DEBUG
J 0
(-2400 5400);
DISPLAY 1.617021 (-2400 5400);
PAINT WHITE (-2400 5400);
DISPLAY INVISIBLE (-2400 5400);
FORCEPROP 2 LAST ROOM CPU_XDP_DEBUG
J 0
(-2400 5400);
DISPLAY 1.617021 (-2400 5400);
PAINT WHITE (-2400 5400);
DISPLAY INVISIBLE (-2400 5400);
FORCEPROP 1 LAST OFFPAGE TRUE
J 0
(-2275 5225);
PAINT GREEN (-2275 5225);
DISPLAY INVISIBLE (-2275 5225);
FORCEPROP 1 LAST COMMENT_BODY TRUE
J 0
(-2645 5255);
DISPLAY 1.893617 (-2645 5255);
PAINT PEACH (-2645 5255);
DISPLAY INVISIBLE (-2645 5255);
FORCEADD OFFPAGE..2
(-2600 5450);
FORCEPROP 2 LAST $XR2 112 
J 0
(-2171 5450);
DISPLAY 0.638298 (-2171 5450);
PAINT MONO (-2171 5450);
FORCEPROP 2 LAST $XR1 118 
J 0
(-2291 5450);
DISPLAY 0.638298 (-2291 5450);
PAINT MONO (-2291 5450);
FORCEPROP 2 LAST $XR0 111 
J 0
(-2411 5450);
DISPLAY 0.638298 (-2411 5450);
PAINT MONO (-2411 5450);
FORCEPROP 2 LAST PATH I46
J 0
(-2150 5500);
DISPLAY 1.021277 (-2150 5500);
PAINT ORANGE (-2150 5500);
DISPLAY INVISIBLE (-2150 5500);
FORCEPROP 2 LAST CDS_LIB mstr_standard
J 0
(-2600 5450);
DISPLAY 2.212766 (-2600 5450);
PAINT ORANGE (-2600 5450);
DISPLAY INVISIBLE (-2600 5450);
FORCEPROP 2 LAST BOM_COST DEBUG
J 0
(-2400 5500);
DISPLAY 1.617021 (-2400 5500);
PAINT WHITE (-2400 5500);
DISPLAY INVISIBLE (-2400 5500);
FORCEPROP 2 LAST ROOM CPU_XDP_DEBUG
J 0
(-2400 5500);
DISPLAY 1.617021 (-2400 5500);
PAINT WHITE (-2400 5500);
DISPLAY INVISIBLE (-2400 5500);
FORCEPROP 1 LAST OFFPAGE TRUE
J 0
(-2275 5325);
PAINT GREEN (-2275 5325);
DISPLAY INVISIBLE (-2275 5325);
FORCEPROP 1 LAST COMMENT_BODY TRUE
J 0
(-2645 5355);
DISPLAY 1.893617 (-2645 5355);
PAINT PEACH (-2645 5355);
DISPLAY INVISIBLE (-2645 5355);
FORCEADD OFFPAGE..2
(-2600 5400);
FORCEPROP 2 LAST $XR3 56 
J 0
(-2081 5400);
DISPLAY 0.638298 (-2081 5400);
PAINT MONO (-2081 5400);
FORCEPROP 2 LAST $XR2 22 
J 0
(-2171 5400);
DISPLAY 0.638298 (-2171 5400);
PAINT MONO (-2171 5400);
FORCEPROP 2 LAST $XR1 118 
J 0
(-2291 5400);
DISPLAY 0.638298 (-2291 5400);
PAINT MONO (-2291 5400);
FORCEPROP 2 LAST $XR0 111 
J 0
(-2411 5400);
DISPLAY 0.638298 (-2411 5400);
PAINT MONO (-2411 5400);
FORCEPROP 2 LAST PATH I47
J 0
(-2075 5450);
DISPLAY 1.021277 (-2075 5450);
PAINT ORANGE (-2075 5450);
DISPLAY INVISIBLE (-2075 5450);
FORCEPROP 2 LAST CDS_LIB mstr_standard
J 0
(-2600 5400);
DISPLAY 2.212766 (-2600 5400);
PAINT ORANGE (-2600 5400);
DISPLAY INVISIBLE (-2600 5400);
FORCEPROP 2 LAST BOM_COST DEBUG
J 0
(-2400 5450);
DISPLAY 1.617021 (-2400 5450);
PAINT WHITE (-2400 5450);
DISPLAY INVISIBLE (-2400 5450);
FORCEPROP 2 LAST ROOM CPU_XDP_DEBUG
J 0
(-2400 5450);
DISPLAY 1.617021 (-2400 5450);
PAINT WHITE (-2400 5450);
DISPLAY INVISIBLE (-2400 5450);
FORCEPROP 1 LAST OFFPAGE TRUE
J 0
(-2275 5275);
PAINT GREEN (-2275 5275);
DISPLAY INVISIBLE (-2275 5275);
FORCEPROP 1 LAST COMMENT_BODY TRUE
J 0
(-2645 5305);
DISPLAY 1.893617 (-2645 5305);
PAINT PEACH (-2645 5305);
DISPLAY INVISIBLE (-2645 5305);
FORCEADD OFFPAGE..2
(-2600 5500);
FORCEPROP 2 LAST $XR2 112 
J 0
(-2171 5500);
DISPLAY 0.638298 (-2171 5500);
PAINT MONO (-2171 5500);
FORCEPROP 2 LAST $XR1 118 
J 0
(-2291 5500);
DISPLAY 0.638298 (-2291 5500);
PAINT MONO (-2291 5500);
FORCEPROP 2 LAST $XR0 111 
J 0
(-2411 5500);
DISPLAY 0.638298 (-2411 5500);
PAINT MONO (-2411 5500);
FORCEPROP 2 LAST PATH I48
J 0
(-2150 5550);
DISPLAY 1.021277 (-2150 5550);
PAINT ORANGE (-2150 5550);
DISPLAY INVISIBLE (-2150 5550);
FORCEPROP 2 LAST ROOM CPU_XDP_DEBUG
J 0
(-2400 5550);
DISPLAY 1.617021 (-2400 5550);
PAINT WHITE (-2400 5550);
DISPLAY INVISIBLE (-2400 5550);
FORCEPROP 2 LAST BOM_COST DEBUG
J 0
(-2400 5550);
DISPLAY 1.617021 (-2400 5550);
PAINT WHITE (-2400 5550);
DISPLAY INVISIBLE (-2400 5550);
FORCEPROP 2 LAST CDS_LIB mstr_standard
J 0
(-2600 5500);
DISPLAY 2.212766 (-2600 5500);
PAINT ORANGE (-2600 5500);
DISPLAY INVISIBLE (-2600 5500);
FORCEPROP 1 LAST OFFPAGE TRUE
J 0
(-2275 5375);
PAINT GREEN (-2275 5375);
DISPLAY INVISIBLE (-2275 5375);
FORCEPROP 1 LAST COMMENT_BODY TRUE
J 0
(-2645 5405);
DISPLAY 1.893617 (-2645 5405);
PAINT PEACH (-2645 5405);
DISPLAY INVISIBLE (-2645 5405);
FORCEADD GTL2014..1
(-4950 5500);
FORCEPROP 2 LASTPIN (-5400 5350) $PN 13
J 2
(-5410 5360);
DISPLAY 0.617021 (-5410 5360);
PAINT WHITE (-5410 5360);
FORCEPROP 2 LASTPIN (-4500 5450) $PN 5
J 0
(-4490 5460);
DISPLAY 0.617021 (-4490 5460);
PAINT WHITE (-4490 5460);
FORCEPROP 2 LASTPIN (-4500 5400) $PN 3
J 0
(-4490 5410);
DISPLAY 0.617021 (-4490 5410);
PAINT WHITE (-4490 5410);
FORCEPROP 2 LASTPIN (-5400 5800) $PN 14
J 2
(-5410 5810);
DISPLAY 0.617021 (-5410 5810);
PAINT WHITE (-5410 5810);
FORCEPROP 2 LASTPIN (-5400 5500) $PN 9
J 2
(-5410 5510);
DISPLAY 0.617021 (-5410 5510);
PAINT WHITE (-5410 5510);
FORCEPROP 2 LASTPIN (-4500 5500) $PN 6
J 0
(-4490 5510);
DISPLAY 0.617021 (-4490 5510);
PAINT WHITE (-4490 5510);
FORCEPROP 2 LASTPIN (-4500 5350) $PN 2
J 0
(-4490 5360);
DISPLAY 0.617021 (-4490 5360);
PAINT WHITE (-4490 5360);
FORCEPROP 2 LASTPIN (-4500 5100) $PN 7
J 0
(-4490 5110);
DISPLAY 0.617021 (-4490 5110);
PAINT WHITE (-4490 5110);
FORCEPROP 2 LASTPIN (-4500 5150) $PN 8
J 0
(-4490 5160);
DISPLAY 0.617021 (-4490 5160);
PAINT WHITE (-4490 5160);
FORCEPROP 2 LASTPIN (-4500 5200) $PN 11
J 0
(-4490 5210);
DISPLAY 0.617021 (-4490 5210);
PAINT WHITE (-4490 5210);
FORCEPROP 2 LASTPIN (-5400 5750) $PN 4
J 2
(-5410 5760);
DISPLAY 0.617021 (-5410 5760);
PAINT WHITE (-5410 5760);
FORCEPROP 1 LAST MATERIAL IC
J 0
(-5350 6000);
DISPLAY 0.617021 (-5350 6000);
PAINT SKYBLUE (-5350 6000);
FORCEPROP 2 LASTPIN (-5400 5450) $PN 10
J 2
(-5410 5460);
DISPLAY 0.617021 (-5410 5460);
PAINT WHITE (-5410 5460);
FORCEPROP 2 LASTPIN (-5400 5400) $PN 12
J 2
(-5410 5410);
DISPLAY 0.617021 (-5410 5410);
PAINT WHITE (-5410 5410);
FORCEPROP 2 LASTPIN (-5400 5650) $PN 1
J 2
(-5410 5660);
DISPLAY 0.617021 (-5410 5660);
PAINT WHITE (-5410 5660);
FORCEPROP 1 LAST LOCATION U25W10
J 0
(-5350 6050);
DISPLAY 0.617021 (-5350 6050);
PAINT AQUA (-5350 6050);
FORCEPROP 1 LAST PART_NUMBER D66151-001
J 0
(-5050 5000);
DISPLAY 0.617021 (-5050 5000);
PAINT BLUE (-5050 5000);
FORCEPROP 2 LAST CDS_LOCATION U25W10
J 0
(-5350 6050);
DISPLAY 0.617021 (-5350 6050);
PAINT AQUA (-5350 6050);
DISPLAY INVISIBLE (-5350 6050);
FORCEPROP 1 LAST PACK_TYPE SM
J 0
(-5350 6100);
DISPLAY 1.617021 (-5350 6100);
PAINT SKYBLUE (-5350 6100);
DISPLAY INVISIBLE (-5350 6100);
FORCEPROP 2 LAST BOM_COST PROC_SIDEBAND
J 0
(-4950 5500);
DISPLAY 1.617021 (-4950 5500);
PAINT WHITE (-4950 5500);
DISPLAY INVISIBLE (-4950 5500);
FORCEPROP 2 LAST CDS_LIB mstr_digital
J 0
(-4950 5500);
DISPLAY 1.617021 (-4950 5500);
PAINT MONO (-4950 5500);
DISPLAY INVISIBLE (-4950 5500);
FORCEPROP 2 LAST CDS_SEC 1
J 2
(-5350 6100);
DISPLAY 2.276596 (-5350 6100);
PAINT ORANGE (-5350 6100);
DISPLAY INVISIBLE (-5350 6100);
FORCEPROP 2 LAST $SEC 1
J 2
(-5350 6100);
DISPLAY 1.510638 (-5350 6100);
PAINT MONO (-5350 6100);
DISPLAY INVISIBLE (-5350 6100);
FORCEPROP 2 LAST ROOM PROC_RSTS_PGOODS
J 2
(-5350 6100);
DISPLAY 2.276596 (-5350 6100);
PAINT WHITE (-5350 6100);
DISPLAY INVISIBLE (-5350 6100);
FORCEPROP 1 LAST PATH I49
J 0
(-4950 6000);
PAINT GREEN (-4950 6000);
DISPLAY INVISIBLE (-4950 6000);
FORCEADD OFFPAGE..1
(-7750 5400);
FORCEPROP 2 LAST $XR0 255 
J 0
(-8002 5400);
DISPLAY 0.638298 (-8002 5400);
PAINT MONO (-8002 5400);
FORCEPROP 2 LAST CDS_LIB mstr_standard
J 0
(-7750 5400);
PAINT ORANGE (-7750 5400);
DISPLAY INVISIBLE (-7750 5400);
FORCEPROP 2 LAST PATH I50
J 0
(-8000 5450);
DISPLAY 1.021277 (-8000 5450);
PAINT ORANGE (-8000 5450);
DISPLAY INVISIBLE (-8000 5450);
FORCEPROP 1 LAST OFFPAGE TRUE
J 0
(-7425 5275);
DISPLAY 1.404255 (-7425 5275);
PAINT GREEN (-7425 5275);
DISPLAY INVISIBLE (-7425 5275);
FORCEPROP 1 LAST COMMENT_BODY TRUE
J 0
(-7625 5300);
DISPLAY 1.404255 (-7625 5300);
PAINT PEACH (-7625 5300);
DISPLAY INVISIBLE (-7625 5300);
FORCEADD OFFPAGE..1
(-7750 5350);
FORCEPROP 2 LAST $XR0 254 
J 0
(-8002 5350);
DISPLAY 0.638298 (-8002 5350);
PAINT MONO (-8002 5350);
FORCEPROP 2 LAST CDS_LIB mstr_standard
J 0
(-7750 5350);
PAINT ORANGE (-7750 5350);
DISPLAY INVISIBLE (-7750 5350);
FORCEPROP 2 LAST PATH I51
J 0
(-8000 5400);
DISPLAY 1.021277 (-8000 5400);
PAINT ORANGE (-8000 5400);
DISPLAY INVISIBLE (-8000 5400);
FORCEPROP 1 LAST OFFPAGE TRUE
J 0
(-7425 5225);
DISPLAY 1.404255 (-7425 5225);
PAINT GREEN (-7425 5225);
DISPLAY INVISIBLE (-7425 5225);
FORCEPROP 1 LAST COMMENT_BODY TRUE
J 0
(-7625 5250);
DISPLAY 1.404255 (-7625 5250);
PAINT PEACH (-7625 5250);
DISPLAY INVISIBLE (-7625 5250);
FORCEADD OFFPAGE..1
(-8950 3600);
FORCEPROP 2 LAST $XR0 146 
J 0
(-9202 3600);
DISPLAY 0.638298 (-9202 3600);
PAINT MONO (-9202 3600);
FORCEPROP 2 LAST PATH I52
J 0
(-9200 3650);
DISPLAY 1.021277 (-9200 3650);
PAINT ORANGE (-9200 3650);
DISPLAY INVISIBLE (-9200 3650);
FORCEPROP 2 LAST CDS_LIB mstr_standard
J 0
(-8950 3600);
PAINT ORANGE (-8950 3600);
DISPLAY INVISIBLE (-8950 3600);
FORCEPROP 1 LAST OFFPAGE TRUE
J 0
(-8625 3475);
DISPLAY 1.404255 (-8625 3475);
PAINT GREEN (-8625 3475);
DISPLAY INVISIBLE (-8625 3475);
FORCEPROP 1 LAST COMMENT_BODY TRUE
J 0
(-8825 3500);
DISPLAY 1.404255 (-8825 3500);
PAINT PEACH (-8825 3500);
DISPLAY INVISIBLE (-8825 3500);
FORCEADD MAX4564EKA-GP..1
(-7075 3625);
FORCEPROP 2 LASTPIN (-7450 3650) $PN 2
J 2
(-7460 3660);
DISPLAY 0.808511 (-7460 3660);
PAINT ORANGE (-7460 3660);
FORCEPROP 2 LASTPIN (-7450 3600) $PN 3
J 2
(-7460 3610);
DISPLAY 0.808511 (-7460 3610);
PAINT ORANGE (-7460 3610);
FORCEPROP 2 LASTPIN (-6700 3700) $PN 8
J 0
(-6690 3710);
DISPLAY 0.808511 (-6690 3710);
PAINT ORANGE (-6690 3710);
FORCEPROP 2 LASTPIN (-6700 3600) $PN 6
J 0
(-6690 3610);
DISPLAY 0.808511 (-6690 3610);
PAINT ORANGE (-6690 3610);
FORCEPROP 2 LASTPIN (-6700 3550) $PN 5
J 0
(-6690 3560);
DISPLAY 0.808511 (-6690 3560);
PAINT ORANGE (-6690 3560);
FORCEPROP 2 LASTPIN (-6700 3650) $PN 7
J 0
(-6690 3660);
DISPLAY 0.808511 (-6690 3660);
PAINT ORANGE (-6690 3660);
FORCEPROP 2 LASTPIN (-7450 3700) $PN 1
J 2
(-7460 3710);
DISPLAY 0.808511 (-7460 3710);
PAINT ORANGE (-7460 3710);
FORCEPROP 2 LASTPIN (-7450 3550) $PN 4
J 2
(-7460 3560);
DISPLAY 0.808511 (-7460 3560);
PAINT ORANGE (-7460 3560);
FORCEPROP 1 LAST LOCATION U25W13
J 0
(-7275 3825);
DISPLAY 0.617021 (-7275 3825);
PAINT GREEN (-7275 3825);
FORCEPROP 1 LAST VALUE MAX4564EKA-GP
J 0
(-7275 3400);
DISPLAY 0.617021 (-7275 3400);
PAINT GREEN (-7275 3400);
FORCEPROP 1 LAST CDS_LMAN_SYM_OUTLINE -225,175,225,-175
J 0
(-7075 3625);
DISPLAY 0.468085 (-7075 3625);
PAINT GREEN (-7075 3625);
DISPLAY INVISIBLE (-7075 3625);
FORCEPROP 1 LAST PATH I53
J 0
(-7075 3949);
DISPLAY 0.617021 (-7075 3949);
PAINT GREEN (-7075 3949);
DISPLAY INVISIBLE (-7075 3949);
FORCEPROP 2 LAST CDS_LIB w_hdl
J 0
(-7075 3625);
DISPLAY INVISIBLE (-7075 3625);
FORCEPROP 1 LAST PART_NUMBER 074.04564.0099
J 0
(-7075 3305);
DISPLAY 0.617021 (-7075 3305);
PAINT GREEN (-7075 3305);
DISPLAY INVISIBLE (-7075 3305);
FORCEPROP 2 LAST SEC_TYPE SCRET-GC1
J 0
(-7075 4000);
DISPLAY 1.021277 (-7075 4000);
PAINT ORANGE (-7075 4000);
DISPLAY INVISIBLE (-7075 4000);
FORCEPROP 2 LAST SEC 1
J 0
(-7075 4000);
DISPLAY 0.680851 (-7075 4000);
PAINT MONO (-7075 4000);
DISPLAY INVISIBLE (-7075 4000);
FORCEPROP 1 LAST PACK_TYPE SCRET-GC1
J 0
(-7075 3625);
DISPLAY 0.617021 (-7075 3625);
PAINT GREEN (-7075 3625);
DISPLAY INVISIBLE (-7075 3625);
FORCEADD GND..1
(-6600 3475);
FORCEPROP 3 LASTPIN (-6600 3525) SIG_NAME GND\g
J 0
(-6590 3535);
DISPLAY 0.659574 (-6590 3535);
PAINT MONO (-6590 3535);
DISPLAY INVISIBLE (-6590 3535);
FORCEPROP 1 LAST PATH I54
J 0
(-6525 3475);
DISPLAY 0.872340 (-6525 3475);
PAINT AQUA (-6525 3475);
DISPLAY INVISIBLE (-6525 3475);
FORCEPROP 1 LAST SIZE 1B
J 0
(-6525 3425);
DISPLAY 0.872340 (-6525 3425);
PAINT AQUA (-6525 3425);
DISPLAY INVISIBLE (-6525 3425);
FORCEPROP 1 LAST VOLTAGE 0.0V
J 0
(-6645 3432);
DISPLAY 0.340426 (-6645 3432);
PAINT SKYBLUE (-6645 3432);
DISPLAY INVISIBLE (-6645 3432);
FORCEPROP 2 LAST CDS_LIB mstr_symbols
J 0
(-6600 3475);
PAINT ORANGE (-6600 3475);
DISPLAY INVISIBLE (-6600 3475);
FORCEPROP 1 LAST BODY_TYPE PLUMBING
J 0
(-6645 3432);
DISPLAY 0.340426 (-6645 3432);
PAINT GREEN (-6645 3432);
DISPLAY INVISIBLE (-6645 3432);
FORCEPROP 1 LAST HDL_POWER GND
J 0
(-6600 3625);
DISPLAY 0.872340 (-6600 3625);
PAINT GREEN (-6600 3625);
DISPLAY INVISIBLE (-6600 3625);
FORCEADD CAP_A..1
(-8700 3850);
FORCEPROP 1 LAST VALUE 0.1UF
J 0
(-8650 3900);
DISPLAY 0.617021 (-8650 3900);
PAINT SKYBLUE (-8650 3900);
FORCEPROP 1 LAST PART_NUMBER A36096-030
J 0
(-8650 3700);
DISPLAY 0.617021 (-8650 3700);
PAINT BLUE (-8650 3700);
FORCEPROP 1 LAST PACK_TYPE 0402V
J 0
(-8650 3650);
DISPLAY 0.617021 (-8650 3650);
PAINT SKYBLUE (-8650 3650);
FORCEPROP 1 LAST MATERIAL X7R
J 0
(-8650 3750);
DISPLAY 0.617021 (-8650 3750);
PAINT SKYBLUE (-8650 3750);
FORCEPROP 1 LASTPIN (-8700 3750) $PN 2
J 0
(-8690 3730);
DISPLAY 0.617021 (-8690 3730);
PAINT ORANGE (-8690 3730);
FORCEPROP 1 LASTPIN (-8700 3950) $PN 1
J 0
(-8690 3930);
DISPLAY 0.617021 (-8690 3930);
PAINT ORANGE (-8690 3930);
FORCEPROP 1 LAST TOLERANCE 10%
J 0
(-8650 3800);
DISPLAY 0.617021 (-8650 3800);
PAINT SKYBLUE (-8650 3800);
FORCEPROP 1 LAST LOCATION C25W95
J 0
(-8650 3950);
DISPLAY 0.617021 (-8650 3950);
PAINT AQUA (-8650 3950);
FORCEPROP 1 LAST VOLTAGE 16V
J 0
(-8650 3850);
DISPLAY 0.617021 (-8650 3850);
PAINT SKYBLUE (-8650 3850);
FORCEPROP 1 LAST PATH I56
J 0
(-8650 4000);
DISPLAY 0.978723 (-8650 4000);
PAINT WHITE (-8650 4000);
DISPLAY INVISIBLE (-8650 4000);
FORCEPROP 2 LAST CDS_LOCATION C25W95
J 0
(-8650 3950);
DISPLAY 0.617021 (-8650 3950);
PAINT AQUA (-8650 3950);
DISPLAY INVISIBLE (-8650 3950);
FORCEPROP 2 LAST ROOM UART_MUX
J 0
(-8650 4000);
DISPLAY 1.021277 (-8650 4000);
PAINT ORANGE (-8650 4000);
DISPLAY INVISIBLE (-8650 4000);
FORCEPROP 2 LAST SEC 1
J 0
(-8650 4050);
DISPLAY 0.680851 (-8650 4050);
PAINT MONO (-8650 4050);
DISPLAY INVISIBLE (-8650 4050);
FORCEPROP 2 LAST CDS_SEC 1
J 0
(-8650 4000);
PAINT ORANGE (-8650 4000);
DISPLAY INVISIBLE (-8650 4000);
FORCEPROP 2 LAST BOM_COST DEBUG
J 0
(-8650 4050);
DISPLAY 1.021277 (-8650 4050);
PAINT ORANGE (-8650 4050);
DISPLAY INVISIBLE (-8650 4050);
FORCEPROP 2 LAST SEC_TYPE 0402V
J 0
(-8650 4050);
DISPLAY 1.021277 (-8650 4050);
PAINT ORANGE (-8650 4050);
DISPLAY INVISIBLE (-8650 4050);
FORCEPROP 2 LAST CDS_LIB dev_discrete
J 0
(-8700 3850);
PAINT ORANGE (-8700 3850);
DISPLAY INVISIBLE (-8700 3850);
FORCEADD GND..1
(-8700 3675);
FORCEPROP 3 LASTPIN (-8700 3725) SIG_NAME GND\g
J 0
(-8690 3735);
DISPLAY 0.659574 (-8690 3735);
PAINT MONO (-8690 3735);
DISPLAY INVISIBLE (-8690 3735);
FORCEPROP 1 LAST PATH I57
J 0
(-8625 3675);
DISPLAY 0.872340 (-8625 3675);
PAINT AQUA (-8625 3675);
DISPLAY INVISIBLE (-8625 3675);
FORCEPROP 1 LAST SIZE 1B
J 0
(-8625 3625);
DISPLAY 0.872340 (-8625 3625);
PAINT AQUA (-8625 3625);
DISPLAY INVISIBLE (-8625 3625);
FORCEPROP 1 LAST VOLTAGE 0.0V
J 0
(-8745 3632);
DISPLAY 0.340426 (-8745 3632);
PAINT SKYBLUE (-8745 3632);
DISPLAY INVISIBLE (-8745 3632);
FORCEPROP 2 LAST CDS_LIB mstr_symbols
J 0
(-8700 3675);
PAINT ORANGE (-8700 3675);
DISPLAY INVISIBLE (-8700 3675);
FORCEPROP 1 LAST BODY_TYPE PLUMBING
J 0
(-8745 3632);
DISPLAY 0.340426 (-8745 3632);
PAINT GREEN (-8745 3632);
DISPLAY INVISIBLE (-8745 3632);
FORCEPROP 1 LAST HDL_POWER GND
J 0
(-8700 3825);
DISPLAY 0.872340 (-8700 3825);
PAINT GREEN (-8700 3825);
DISPLAY INVISIBLE (-8700 3825);
FORCEADD P3V3_STBY..1
(-8700 4150);
FORCEPROP 3 LASTPIN (-8700 4100) SIG_NAME P3V3_STBY\g
J 0
(-8690 4110);
DISPLAY 0.659574 (-8690 4110);
PAINT MONO (-8690 4110);
DISPLAY INVISIBLE (-8690 4110);
FORCEPROP 1 LAST VOLTAGE 3.3V
J 0
(-8745 4107);
DISPLAY 0.340426 (-8745 4107);
PAINT SKYBLUE (-8745 4107);
DISPLAY INVISIBLE (-8745 4107);
FORCEPROP 2 LAST CDS_LIB mstr_symbols
J 0
(-8700 4150);
PAINT MONO (-8700 4150);
DISPLAY INVISIBLE (-8700 4150);
FORCEPROP 1 LAST SIZE 1B
J 0
(-8655 4172);
DISPLAY 0.340426 (-8655 4172);
PAINT GREEN (-8655 4172);
DISPLAY INVISIBLE (-8655 4172);
FORCEPROP 1 LAST PATH I58
J 0
(-8655 4152);
DISPLAY 0.340426 (-8655 4152);
PAINT GREEN (-8655 4152);
DISPLAY INVISIBLE (-8655 4152);
FORCEPROP 1 LAST BODY_TYPE PLUMBING
J 0
(-8745 4107);
DISPLAY 0.340426 (-8745 4107);
PAINT GREEN (-8745 4107);
DISPLAY INVISIBLE (-8745 4107);
FORCEPROP 1 LAST HDL_POWER P3V3_STBY
J 0
(-9000 4025);
DISPLAY 0.872340 (-9000 4025);
PAINT ORANGE (-9000 4025);
DISPLAY INVISIBLE (-9000 4025);
FORCEADD OFFPAGE..1
(-7150 4050);
FORCEPROP 2 LAST $XR2 255 
J 0
(-7402 4086);
DISPLAY 0.638298 (-7402 4086);
PAINT MONO (-7402 4086);
FORCEPROP 2 LAST $XR1 189 
J 0
(-7402 4014);
DISPLAY 0.638298 (-7402 4014);
PAINT MONO (-7402 4014);
FORCEPROP 2 LAST $XR0 148 
J 0
(-7402 4050);
DISPLAY 0.638298 (-7402 4050);
PAINT MONO (-7402 4050);
FORCEPROP 2 LAST PATH I59
J 0
(-7400 4100);
DISPLAY 1.021277 (-7400 4100);
PAINT ORANGE (-7400 4100);
DISPLAY INVISIBLE (-7400 4100);
FORCEPROP 2 LAST CDS_LIB mstr_standard
J 0
(-7150 4050);
PAINT ORANGE (-7150 4050);
DISPLAY INVISIBLE (-7150 4050);
FORCEPROP 1 LAST OFFPAGE TRUE
J 0
(-6825 3925);
DISPLAY 1.404255 (-6825 3925);
PAINT GREEN (-6825 3925);
DISPLAY INVISIBLE (-6825 3925);
FORCEPROP 1 LAST COMMENT_BODY TRUE
J 0
(-7025 3950);
DISPLAY 1.404255 (-7025 3950);
PAINT PEACH (-7025 3950);
DISPLAY INVISIBLE (-7025 3950);
FORCEADD P3V3_STBY..1
(-3050 3200);
FORCEPROP 3 LASTPIN (-3050 3150) SIG_NAME P3V3_STBY\g
J 0
(-3040 3160);
DISPLAY 0.659574 (-3040 3160);
PAINT MONO (-3040 3160);
DISPLAY INVISIBLE (-3040 3160);
FORCEPROP 1 LAST PATH I60
J 0
(-3005 3202);
DISPLAY 0.340426 (-3005 3202);
PAINT GREEN (-3005 3202);
DISPLAY INVISIBLE (-3005 3202);
FORCEPROP 1 LAST VOLTAGE 3.3V
J 0
(-3095 3157);
DISPLAY 0.340426 (-3095 3157);
PAINT SKYBLUE (-3095 3157);
DISPLAY INVISIBLE (-3095 3157);
FORCEPROP 2 LAST CDS_LIB mstr_symbols
J 0
(-3050 3200);
PAINT MONO (-3050 3200);
DISPLAY INVISIBLE (-3050 3200);
FORCEPROP 1 LAST SIZE 1B
J 0
(-3005 3222);
DISPLAY 0.340426 (-3005 3222);
PAINT GREEN (-3005 3222);
DISPLAY INVISIBLE (-3005 3222);
FORCEPROP 1 LAST BODY_TYPE PLUMBING
J 0
(-3095 3157);
DISPLAY 0.340426 (-3095 3157);
PAINT GREEN (-3095 3157);
DISPLAY INVISIBLE (-3095 3157);
FORCEPROP 1 LAST HDL_POWER P3V3_STBY
J 0
(-3350 3075);
DISPLAY 0.872340 (-3350 3075);
PAINT ORANGE (-3350 3075);
DISPLAY INVISIBLE (-3350 3075);
FORCEADD TTL1G08..1
(-5100 4000);
FORCEPROP 1 LAST POWER_GROUP VCC=P3V3_STBY;GND=GND;
J 1
(-5075 3825);
DISPLAY 0.617021 (-5075 3825);
PAINT ORANGE (-5075 3825);
FORCEPROP 2 LASTPIN (-5250 4050) $PN 1
J 2
(-5260 4060);
DISPLAY 0.617021 (-5260 4060);
PAINT ORANGE (-5260 4060);
FORCEPROP 2 LASTPIN (-4950 4000) $PN 4
J 0
(-4940 4010);
DISPLAY 0.617021 (-4940 4010);
PAINT ORANGE (-4940 4010);
FORCEPROP 2 LASTPIN (-5250 3950) $PN 2
J 2
(-5260 3960);
DISPLAY 0.617021 (-5260 3960);
PAINT ORANGE (-5260 3960);
FORCEPROP 1 LAST PART_NUMBER D10321-001
J 1
(-5125 4100);
DISPLAY 0.617021 (-5125 4100);
PAINT BLUE (-5125 4100);
FORCEPROP 1 LAST LOCATION U25W17
J 1
(-5125 4135);
DISPLAY 0.617021 (-5125 4135);
PAINT AQUA (-5125 4135);
FORCEPROP 1 LAST MATERIAL IC
J 1
(-5125 4210);
DISPLAY 0.617021 (-5125 4210);
PAINT SKYBLUE (-5125 4210);
FORCEPROP 1 LAST PACK_TYPE SOTLF
J 1
(-5125 4175);
DISPLAY 0.617021 (-5125 4175);
PAINT SKYBLUE (-5125 4175);
FORCEPROP 1 LAST VALUE NC7SZ08
J 1
(-5100 3875);
DISPLAY 0.617021 (-5100 3875);
PAINT SKYBLUE (-5100 3875);
FORCEPROP 1 LAST PATH I61
J 1
(-5120 4265);
DISPLAY 0.702128 (-5120 4265);
PAINT WHITE (-5120 4265);
DISPLAY INVISIBLE (-5120 4265);
FORCEPROP 0 LAST BOM_COST PROC_SIDEBAND
J 0
(-5125 4400);
DISPLAY 1.021277 (-5125 4400);
PAINT ORANGE (-5125 4400);
DISPLAY INVISIBLE (-5125 4400);
FORCEPROP 2 LAST CDS_LIB mstr_ttl
J 0
(-5100 4000);
PAINT ORANGE (-5100 4000);
DISPLAY INVISIBLE (-5100 4000);
FORCEPROP 2 LAST SEC_TYPE SOTLF
J 0
(-5100 4300);
DISPLAY 1.021277 (-5100 4300);
PAINT ORANGE (-5100 4300);
DISPLAY INVISIBLE (-5100 4300);
FORCEPROP 2 LAST SEC 1
J 0
(-5100 4300);
DISPLAY 0.680851 (-5100 4300);
PAINT MONO (-5100 4300);
DISPLAY INVISIBLE (-5100 4300);
FORCEPROP 0 LAST ROOM CAT_ERR
J 0
(-5125 4300);
DISPLAY 1.021277 (-5125 4300);
PAINT ORANGE (-5125 4300);
DISPLAY INVISIBLE (-5125 4300);
FORCEPROP 0 LAST CDS_SEC 1
J 0
(-5125 4250);
DISPLAY INVISIBLE (-5125 4250);
FORCEPROP 2 LAST CDS_LOCATION U25W17
J 1
(-5125 4135);
DISPLAY 0.617021 (-5125 4135);
PAINT AQUA (-5125 4135);
DISPLAY INVISIBLE (-5125 4135);
FORCEADD CAP_A..1
(-5350 4450);
FORCEPROP 1 LAST TOLERANCE 10%
J 0
(-5300 4400);
DISPLAY 0.617021 (-5300 4400);
PAINT SKYBLUE (-5300 4400);
FORCEPROP 1 LAST PART_NUMBER A36096-030
J 0
(-5300 4300);
DISPLAY 0.617021 (-5300 4300);
PAINT BLUE (-5300 4300);
FORCEPROP 1 LAST PACK_TYPE 0402V
J 0
(-5300 4250);
DISPLAY 0.617021 (-5300 4250);
PAINT SKYBLUE (-5300 4250);
FORCEPROP 1 LASTPIN (-5350 4550) $PN 1
J 0
(-5340 4530);
DISPLAY 0.617021 (-5340 4530);
PAINT ORANGE (-5340 4530);
FORCEPROP 1 LAST VALUE 0.1UF
J 0
(-5300 4500);
DISPLAY 0.617021 (-5300 4500);
PAINT SKYBLUE (-5300 4500);
FORCEPROP 1 LAST LOCATION C25W99
J 0
(-5300 4550);
DISPLAY 0.617021 (-5300 4550);
PAINT AQUA (-5300 4550);
FORCEPROP 1 LASTPIN (-5350 4350) $PN 2
J 0
(-5340 4330);
DISPLAY 0.617021 (-5340 4330);
PAINT ORANGE (-5340 4330);
FORCEPROP 1 LAST MATERIAL X7R
J 0
(-5300 4350);
DISPLAY 0.617021 (-5300 4350);
PAINT SKYBLUE (-5300 4350);
FORCEPROP 1 LAST VOLTAGE 16V
J 0
(-5300 4450);
DISPLAY 0.617021 (-5300 4450);
PAINT SKYBLUE (-5300 4450);
FORCEPROP 2 LAST CDS_LOCATION C25W99
J 0
(-5300 4550);
DISPLAY 0.617021 (-5300 4550);
PAINT AQUA (-5300 4550);
DISPLAY INVISIBLE (-5300 4550);
FORCEPROP 1 LAST PATH I62
J 0
(-5300 4600);
DISPLAY 0.978723 (-5300 4600);
PAINT WHITE (-5300 4600);
DISPLAY INVISIBLE (-5300 4600);
FORCEPROP 2 LAST SEC 1
J 0
(-5300 4650);
DISPLAY 0.680851 (-5300 4650);
PAINT MONO (-5300 4650);
DISPLAY INVISIBLE (-5300 4650);
FORCEPROP 2 LAST SEC_TYPE 0402V
J 0
(-5300 4650);
DISPLAY 1.021277 (-5300 4650);
PAINT ORANGE (-5300 4650);
DISPLAY INVISIBLE (-5300 4650);
FORCEPROP 2 LAST CDS_SEC 1
J 0
(-5300 4600);
PAINT ORANGE (-5300 4600);
DISPLAY INVISIBLE (-5300 4600);
FORCEPROP 2 LAST CDS_LIB dev_discrete
J 0
(-5350 4450);
PAINT ORANGE (-5350 4450);
DISPLAY INVISIBLE (-5350 4450);
FORCEPROP 2 LAST BOM_COST PROC_SIDEBAND
J 0
(-5300 4650);
DISPLAY 1.021277 (-5300 4650);
PAINT ORANGE (-5300 4650);
DISPLAY INVISIBLE (-5300 4650);
FORCEPROP 2 LAST ROOM PROC_SIDEBAND
J 0
(-5300 4600);
DISPLAY 1.021277 (-5300 4600);
PAINT ORANGE (-5300 4600);
DISPLAY INVISIBLE (-5300 4600);
FORCEADD GND..1
(-5350 4275);
FORCEPROP 3 LASTPIN (-5350 4325) SIG_NAME GND\g
J 0
(-5340 4335);
DISPLAY 0.659574 (-5340 4335);
PAINT MONO (-5340 4335);
DISPLAY INVISIBLE (-5340 4335);
FORCEPROP 1 LAST PATH I63
J 0
(-5275 4275);
DISPLAY 0.872340 (-5275 4275);
PAINT AQUA (-5275 4275);
DISPLAY INVISIBLE (-5275 4275);
FORCEPROP 2 LAST CDS_LIB mstr_symbols
J 0
(-5350 4275);
PAINT ORANGE (-5350 4275);
DISPLAY INVISIBLE (-5350 4275);
FORCEPROP 1 LAST SIZE 1B
J 0
(-5275 4225);
DISPLAY 0.872340 (-5275 4225);
PAINT AQUA (-5275 4225);
DISPLAY INVISIBLE (-5275 4225);
FORCEPROP 1 LAST VOLTAGE 0.0V
J 0
(-5395 4232);
DISPLAY 0.340426 (-5395 4232);
PAINT SKYBLUE (-5395 4232);
DISPLAY INVISIBLE (-5395 4232);
FORCEPROP 1 LAST BODY_TYPE PLUMBING
J 0
(-5395 4232);
DISPLAY 0.340426 (-5395 4232);
PAINT GREEN (-5395 4232);
DISPLAY INVISIBLE (-5395 4232);
FORCEPROP 1 LAST HDL_POWER GND
J 0
(-5350 4425);
DISPLAY 0.872340 (-5350 4425);
PAINT GREEN (-5350 4425);
DISPLAY INVISIBLE (-5350 4425);
FORCEADD P3V3_STBY..1
(-5350 4650);
FORCEPROP 3 LASTPIN (-5350 4600) SIG_NAME P3V3_STBY\g
J 0
(-5340 4610);
DISPLAY 0.659574 (-5340 4610);
PAINT MONO (-5340 4610);
DISPLAY INVISIBLE (-5340 4610);
FORCEPROP 1 LAST VOLTAGE 3.3V
J 0
(-5395 4607);
DISPLAY 0.340426 (-5395 4607);
PAINT SKYBLUE (-5395 4607);
DISPLAY INVISIBLE (-5395 4607);
FORCEPROP 1 LAST SIZE 1B
J 0
(-5305 4672);
DISPLAY 0.340426 (-5305 4672);
PAINT GREEN (-5305 4672);
DISPLAY INVISIBLE (-5305 4672);
FORCEPROP 2 LAST CDS_LIB mstr_symbols
J 0
(-5350 4650);
PAINT ORANGE (-5350 4650);
DISPLAY INVISIBLE (-5350 4650);
FORCEPROP 1 LAST PATH I64
J 0
(-5305 4652);
DISPLAY 0.340426 (-5305 4652);
PAINT GREEN (-5305 4652);
DISPLAY INVISIBLE (-5305 4652);
FORCEPROP 1 LAST BODY_TYPE PLUMBING
J 0
(-5395 4607);
DISPLAY 0.340426 (-5395 4607);
PAINT GREEN (-5395 4607);
DISPLAY INVISIBLE (-5395 4607);
FORCEPROP 1 LAST HDL_POWER P3V3_STBY
J 0
(-5650 4525);
DISPLAY 0.872340 (-5650 4525);
PAINT ORANGE (-5650 4525);
DISPLAY INVISIBLE (-5650 4525);
FORCEADD OFFPAGE..1
(-5800 4050);
FORCEPROP 2 LAST $XR2 245 
J 0
(-6292 4050);
DISPLAY 0.638298 (-6292 4050);
PAINT MONO (-6292 4050);
FORCEPROP 2 LAST $XR1 189 
J 0
(-6172 4050);
DISPLAY 0.638298 (-6172 4050);
PAINT MONO (-6172 4050);
FORCEPROP 2 LAST $XR0 144 
J 0
(-6052 4050);
DISPLAY 0.638298 (-6052 4050);
PAINT MONO (-6052 4050);
FORCEPROP 2 LAST PATH I65
J 0
(-6075 4100);
DISPLAY 1.021277 (-6075 4100);
PAINT ORANGE (-6075 4100);
DISPLAY INVISIBLE (-6075 4100);
FORCEPROP 2 LAST CDS_LIB mstr_standard
J 0
(-5800 4050);
PAINT ORANGE (-5800 4050);
DISPLAY INVISIBLE (-5800 4050);
FORCEPROP 1 LAST OFFPAGE TRUE
J 0
(-5475 3925);
DISPLAY 1.404255 (-5475 3925);
PAINT GREEN (-5475 3925);
DISPLAY INVISIBLE (-5475 3925);
FORCEPROP 1 LAST COMMENT_BODY TRUE
J 0
(-5675 3950);
DISPLAY 1.404255 (-5675 3950);
PAINT PEACH (-5675 3950);
DISPLAY INVISIBLE (-5675 3950);
FORCEADD OFFPAGE..1
(-5800 3950);
FORCEPROP 2 LAST $XR1 254 
J 0
(-6502 3914);
DISPLAY 0.638298 (-6502 3914);
PAINT MONO (-6502 3914);
FORCEPROP 2 LAST $XR0 255 
J 0
(-6502 3950);
DISPLAY 0.638298 (-6502 3950);
PAINT MONO (-6502 3950);
FORCEPROP 2 LAST CDS_LIB mstr_standard
J 0
(-5800 3950);
PAINT ORANGE (-5800 3950);
DISPLAY INVISIBLE (-5800 3950);
FORCEPROP 2 LAST PATH I66
J 0
(-6075 4000);
DISPLAY 1.021277 (-6075 4000);
PAINT ORANGE (-6075 4000);
DISPLAY INVISIBLE (-6075 4000);
FORCEPROP 1 LAST OFFPAGE TRUE
J 0
(-5475 3825);
DISPLAY 1.404255 (-5475 3825);
PAINT GREEN (-5475 3825);
DISPLAY INVISIBLE (-5475 3825);
FORCEPROP 1 LAST COMMENT_BODY TRUE
J 0
(-5675 3850);
DISPLAY 1.404255 (-5675 3850);
PAINT PEACH (-5675 3850);
DISPLAY INVISIBLE (-5675 3850);
FORCEADD OFFPAGE..1
(-5800 3350);
FORCEPROP 2 LAST $XR0 147 
J 0
(-6052 3350);
DISPLAY 0.638298 (-6052 3350);
PAINT MONO (-6052 3350);
FORCEPROP 2 LAST PATH I67
J 0
(-6050 3425);
DISPLAY 1.021277 (-6050 3425);
PAINT ORANGE (-6050 3425);
DISPLAY INVISIBLE (-6050 3425);
FORCEPROP 2 LAST CDS_LIB mstr_standard
J 0
(-5800 3350);
PAINT ORANGE (-5800 3350);
DISPLAY INVISIBLE (-5800 3350);
FORCEPROP 1 LAST OFFPAGE TRUE
J 0
(-5475 3225);
DISPLAY 1.404255 (-5475 3225);
PAINT GREEN (-5475 3225);
DISPLAY INVISIBLE (-5475 3225);
FORCEPROP 1 LAST COMMENT_BODY TRUE
J 0
(-5675 3250);
DISPLAY 1.404255 (-5675 3250);
PAINT PEACH (-5675 3250);
DISPLAY INVISIBLE (-5675 3250);
FORCEADD GND..1
(-5650 2825);
FORCEPROP 3 LASTPIN (-5650 2875) SIG_NAME GND\g
J 0
(-5640 2885);
DISPLAY 0.659574 (-5640 2885);
PAINT MONO (-5640 2885);
DISPLAY INVISIBLE (-5640 2885);
FORCEPROP 1 LAST VOLTAGE 0.0V
J 0
(-5695 2782);
DISPLAY 0.340426 (-5695 2782);
PAINT SKYBLUE (-5695 2782);
DISPLAY INVISIBLE (-5695 2782);
FORCEPROP 1 LAST SIZE 1B
J 0
(-5575 2775);
DISPLAY 1.893617 (-5575 2775);
PAINT GREEN (-5575 2775);
DISPLAY INVISIBLE (-5575 2775);
FORCEPROP 1 LAST PATH I68
J 0
(-5575 2825);
DISPLAY 0.872340 (-5575 2825);
PAINT AQUA (-5575 2825);
DISPLAY INVISIBLE (-5575 2825);
FORCEPROP 2 LAST CDS_LIB mstr_symbols
J 0
(-5650 2825);
DISPLAY INVISIBLE (-5650 2825);
FORCEPROP 1 LAST BODY_TYPE PLUMBING
J 0
(-5695 2782);
DISPLAY 0.340426 (-5695 2782);
PAINT GREEN (-5695 2782);
DISPLAY INVISIBLE (-5695 2782);
FORCEPROP 1 LAST HDL_POWER GND
J 0
(-5650 2975);
DISPLAY 1.595745 (-5650 2975);
PAINT GREEN (-5650 2975);
DISPLAY INVISIBLE (-5650 2975);
FORCEADD OFFPAGE..1
(-5800 3300);
FORCEPROP 2 LAST $XR1 254 
J 0
(-6052 3264);
DISPLAY 0.638298 (-6052 3264);
PAINT MONO (-6052 3264);
FORCEPROP 2 LAST $XR0 255 
J 0
(-6052 3300);
DISPLAY 0.638298 (-6052 3300);
PAINT MONO (-6052 3300);
FORCEPROP 2 LAST PATH I69
J 0
(-6050 3375);
DISPLAY 1.021277 (-6050 3375);
PAINT ORANGE (-6050 3375);
DISPLAY INVISIBLE (-6050 3375);
FORCEPROP 2 LAST CDS_LIB mstr_standard
J 0
(-5800 3300);
PAINT ORANGE (-5800 3300);
DISPLAY INVISIBLE (-5800 3300);
FORCEPROP 1 LAST OFFPAGE TRUE
J 0
(-5475 3175);
DISPLAY 1.404255 (-5475 3175);
PAINT GREEN (-5475 3175);
DISPLAY INVISIBLE (-5475 3175);
FORCEPROP 1 LAST COMMENT_BODY TRUE
J 0
(-5675 3200);
DISPLAY 1.404255 (-5675 3200);
PAINT PEACH (-5675 3200);
DISPLAY INVISIBLE (-5675 3200);
FORCEADD OFFPAGE..2
(-2100 3500);
FORCEPROP 2 LAST $XR0 254 
J 0
(-1911 3500);
DISPLAY 0.638298 (-1911 3500);
PAINT MONO (-1911 3500);
FORCEPROP 2 LAST PATH I70
J 0
(-1600 3550);
DISPLAY 1.021277 (-1600 3550);
PAINT ORANGE (-1600 3550);
DISPLAY INVISIBLE (-1600 3550);
FORCEPROP 2 LAST ROOM CPU_XDP_DEBUG
J 0
(-1900 3550);
DISPLAY 1.617021 (-1900 3550);
PAINT WHITE (-1900 3550);
DISPLAY INVISIBLE (-1900 3550);
FORCEPROP 2 LAST BOM_COST DEBUG
J 0
(-1900 3550);
DISPLAY 1.617021 (-1900 3550);
PAINT WHITE (-1900 3550);
DISPLAY INVISIBLE (-1900 3550);
FORCEPROP 2 LAST CDS_LIB mstr_standard
J 0
(-2100 3500);
DISPLAY 2.212766 (-2100 3500);
PAINT ORANGE (-2100 3500);
DISPLAY INVISIBLE (-2100 3500);
FORCEPROP 1 LAST OFFPAGE TRUE
J 0
(-1775 3375);
PAINT GREEN (-1775 3375);
DISPLAY INVISIBLE (-1775 3375);
FORCEPROP 1 LAST COMMENT_BODY TRUE
J 0
(-2145 3405);
DISPLAY 1.893617 (-2145 3405);
PAINT PEACH (-2145 3405);
DISPLAY INVISIBLE (-2145 3405);
FORCEADD BLM15AG121SN-1GP..1
R 1
(-2800 3700);
FORCEPROP 2 LASTPIN (-2650 3700) $PN 2
J 0
(-2690 3710);
DISPLAY 0.808511 (-2690 3710);
PAINT ORANGE (-2690 3710);
FORCEPROP 1 LAST VALUE BLM15AG121SN-1GP
J 0
(-2651 3650);
DISPLAY 0.617021 (-2651 3650);
PAINT GREEN (-2651 3650);
FORCEPROP 2 LASTPIN (-2950 3700) $PN 1
J 2
(-2885 3710);
DISPLAY 0.808511 (-2885 3710);
PAINT ORANGE (-2885 3710);
FORCEPROP 1 LAST LOCATION FB25W1
J 0
(-3100 3650);
DISPLAY 0.617021 (-3100 3650);
PAINT GREEN (-3100 3650);
FORCEPROP 1 LAST PACK_TYPE DISCRET-G
R 1
J 0
(-2800 3700);
DISPLAY 0.617021 (-2800 3700);
PAINT GREEN (-2800 3700);
DISPLAY INVISIBLE (-2800 3700);
FORCEPROP 2 LAST SEC 1
J 0
(-2950 3650);
DISPLAY 0.680851 (-2950 3650);
PAINT MONO (-2950 3650);
DISPLAY INVISIBLE (-2950 3650);
FORCEPROP 2 LAST SEC_TYPE DISCRET-G
J 0
(-2950 3650);
DISPLAY 1.021277 (-2950 3650);
PAINT ORANGE (-2950 3650);
DISPLAY INVISIBLE (-2950 3650);
FORCEPROP 1 LAST PART_NUMBER 68.00084.921
R 1
J 0
(-2799 3700);
DISPLAY 0.617021 (-2799 3700);
PAINT GREEN (-2799 3700);
DISPLAY INVISIBLE (-2799 3700);
FORCEPROP 2 LAST CDS_LIB w_hdl
R 1
J 0
(-2800 3700);
DISPLAY INVISIBLE (-2800 3700);
FORCEPROP 1 LAST PATH I71
R 1
J 0
(-2800 3700);
DISPLAY 0.617021 (-2800 3700);
PAINT GREEN (-2800 3700);
DISPLAY INVISIBLE (-2800 3700);
FORCEPROP 1 LAST CDS_LMAN_SYM_OUTLINE -50,100,50,-100
R 1
J 0
(-2800 3700);
DISPLAY 0.468085 (-2800 3700);
PAINT GREEN (-2800 3700);
DISPLAY INVISIBLE (-2800 3700);
FORCEADD BLM15AG121SN-1GP..1
R 1
(-2800 3900);
FORCEPROP 1 LAST VALUE BLM15AG121SN-1GP
J 0
(-2651 3850);
DISPLAY 0.617021 (-2651 3850);
PAINT GREEN (-2651 3850);
FORCEPROP 2 LASTPIN (-2650 3900) $PN 2
J 0
(-2690 3910);
DISPLAY 0.808511 (-2690 3910);
PAINT ORANGE (-2690 3910);
FORCEPROP 1 LAST LOCATION FB25W2
J 0
(-3100 3850);
DISPLAY 0.617021 (-3100 3850);
PAINT GREEN (-3100 3850);
FORCEPROP 2 LASTPIN (-2950 3900) $PN 1
J 2
(-2885 3910);
DISPLAY 0.808511 (-2885 3910);
PAINT ORANGE (-2885 3910);
FORCEPROP 1 LAST PATH I72
R 1
J 0
(-2800 3900);
DISPLAY 0.617021 (-2800 3900);
PAINT GREEN (-2800 3900);
DISPLAY INVISIBLE (-2800 3900);
FORCEPROP 1 LAST CDS_LMAN_SYM_OUTLINE -50,100,50,-100
R 1
J 0
(-2800 3900);
DISPLAY 0.468085 (-2800 3900);
PAINT GREEN (-2800 3900);
DISPLAY INVISIBLE (-2800 3900);
FORCEPROP 2 LAST CDS_LIB w_hdl
R 1
J 0
(-2800 3900);
DISPLAY INVISIBLE (-2800 3900);
FORCEPROP 1 LAST PART_NUMBER 68.00084.921
R 1
J 0
(-2799 3900);
DISPLAY 0.617021 (-2799 3900);
PAINT GREEN (-2799 3900);
DISPLAY INVISIBLE (-2799 3900);
FORCEPROP 2 LAST SEC_TYPE DISCRET-G
J 0
(-2950 3850);
DISPLAY 1.021277 (-2950 3850);
PAINT ORANGE (-2950 3850);
DISPLAY INVISIBLE (-2950 3850);
FORCEPROP 2 LAST SEC 1
J 0
(-2950 3850);
DISPLAY 0.680851 (-2950 3850);
PAINT MONO (-2950 3850);
DISPLAY INVISIBLE (-2950 3850);
FORCEPROP 1 LAST PACK_TYPE DISCRET-G
R 1
J 0
(-2800 3900);
DISPLAY 0.617021 (-2800 3900);
PAINT GREEN (-2800 3900);
DISPLAY INVISIBLE (-2800 3900);
FORCEADD BLM15AG121SN-1GP..1
R 1
(-2800 4100);
FORCEPROP 1 LAST VALUE BLM15AG121SN-1GP
J 0
(-2651 4050);
DISPLAY 0.617021 (-2651 4050);
PAINT GREEN (-2651 4050);
FORCEPROP 2 LASTPIN (-2950 4100) $PN 1
J 2
(-2885 4110);
DISPLAY 0.808511 (-2885 4110);
PAINT ORANGE (-2885 4110);
FORCEPROP 2 LASTPIN (-2650 4100) $PN 2
J 0
(-2690 4110);
DISPLAY 0.808511 (-2690 4110);
PAINT ORANGE (-2690 4110);
FORCEPROP 1 LAST LOCATION FB25W3
J 0
(-3100 4050);
DISPLAY 0.617021 (-3100 4050);
PAINT GREEN (-3100 4050);
FORCEPROP 1 LAST PACK_TYPE DISCRET-G
R 1
J 0
(-2800 4100);
DISPLAY 0.617021 (-2800 4100);
PAINT GREEN (-2800 4100);
DISPLAY INVISIBLE (-2800 4100);
FORCEPROP 2 LAST SEC 1
J 0
(-2950 4050);
DISPLAY 0.680851 (-2950 4050);
PAINT MONO (-2950 4050);
DISPLAY INVISIBLE (-2950 4050);
FORCEPROP 2 LAST SEC_TYPE DISCRET-G
J 0
(-2950 4050);
DISPLAY 1.021277 (-2950 4050);
PAINT ORANGE (-2950 4050);
DISPLAY INVISIBLE (-2950 4050);
FORCEPROP 1 LAST PART_NUMBER 68.00084.921
R 1
J 0
(-2799 4100);
DISPLAY 0.617021 (-2799 4100);
PAINT GREEN (-2799 4100);
DISPLAY INVISIBLE (-2799 4100);
FORCEPROP 2 LAST CDS_LIB w_hdl
R 1
J 0
(-2800 4100);
DISPLAY INVISIBLE (-2800 4100);
FORCEPROP 1 LAST CDS_LMAN_SYM_OUTLINE -50,100,50,-100
R 1
J 0
(-2800 4100);
DISPLAY 0.468085 (-2800 4100);
PAINT GREEN (-2800 4100);
DISPLAY INVISIBLE (-2800 4100);
FORCEPROP 1 LAST PATH I73
R 1
J 0
(-2800 4100);
DISPLAY 0.617021 (-2800 4100);
PAINT GREEN (-2800 4100);
DISPLAY INVISIBLE (-2800 4100);
FORCEADD BLM15AG121SN-1GP..1
R 1
(-3550 5500);
FORCEPROP 1 LAST LOCATION FB25W5
J 0
(-3500 5650);
DISPLAY 0.617021 (-3500 5650);
PAINT GREEN (-3500 5650);
FORCEPROP 1 LAST VALUE BLM15AG121SN-1GP
J 0
(-3501 5600);
DISPLAY 0.617021 (-3501 5600);
PAINT GREEN (-3501 5600);
FORCEPROP 2 LASTPIN (-3700 5500) $PN 1
J 2
(-3635 5510);
DISPLAY 0.808511 (-3635 5510);
PAINT ORANGE (-3635 5510);
FORCEPROP 2 LASTPIN (-3400 5500) $PN 2
J 0
(-3440 5510);
DISPLAY 0.808511 (-3440 5510);
PAINT ORANGE (-3440 5510);
FORCEPROP 1 LAST CDS_LMAN_SYM_OUTLINE -50,100,50,-100
R 1
J 0
(-3550 5500);
DISPLAY 0.468085 (-3550 5500);
PAINT GREEN (-3550 5500);
DISPLAY INVISIBLE (-3550 5500);
FORCEPROP 2 LAST CDS_LIB w_hdl
R 1
J 0
(-3550 5500);
DISPLAY INVISIBLE (-3550 5500);
FORCEPROP 1 LAST PART_NUMBER 68.00084.921
R 1
J 0
(-3549 5500);
DISPLAY 0.617021 (-3549 5500);
PAINT GREEN (-3549 5500);
DISPLAY INVISIBLE (-3549 5500);
FORCEPROP 2 LAST SEC_TYPE DISCRET-G
J 0
(-3700 5450);
DISPLAY 1.021277 (-3700 5450);
PAINT ORANGE (-3700 5450);
DISPLAY INVISIBLE (-3700 5450);
FORCEPROP 2 LAST SEC 1
J 0
(-3700 5450);
DISPLAY 0.680851 (-3700 5450);
PAINT MONO (-3700 5450);
DISPLAY INVISIBLE (-3700 5450);
FORCEPROP 1 LAST PACK_TYPE DISCRET-G
R 1
J 0
(-3550 5500);
DISPLAY 0.617021 (-3550 5500);
PAINT GREEN (-3550 5500);
DISPLAY INVISIBLE (-3550 5500);
FORCEPROP 1 LAST PATH I74
R 1
J 0
(-3550 5500);
DISPLAY 0.617021 (-3550 5500);
PAINT GREEN (-3550 5500);
DISPLAY INVISIBLE (-3550 5500);
FORCEADD BLM15AG121SN-1GP..1
R 1
(-3850 5450);
FORCEPROP 1 LAST VALUE BLM15AG121SN-1GP
J 0
(-4001 5600);
DISPLAY 0.617021 (-4001 5600);
PAINT GREEN (-4001 5600);
FORCEPROP 2 LASTPIN (-4000 5450) $PN 1
J 2
(-3935 5460);
DISPLAY 0.808511 (-3935 5460);
PAINT ORANGE (-3935 5460);
FORCEPROP 2 LASTPIN (-3700 5450) $PN 2
J 0
(-3740 5460);
DISPLAY 0.808511 (-3740 5460);
PAINT ORANGE (-3740 5460);
FORCEPROP 1 LAST LOCATION FB25W4
J 0
(-4000 5650);
DISPLAY 0.617021 (-4000 5650);
PAINT GREEN (-4000 5650);
FORCEPROP 1 LAST PATH I75
R 1
J 0
(-3850 5450);
DISPLAY 0.617021 (-3850 5450);
PAINT GREEN (-3850 5450);
DISPLAY INVISIBLE (-3850 5450);
FORCEPROP 1 LAST PACK_TYPE DISCRET-G
R 1
J 0
(-3850 5450);
DISPLAY 0.617021 (-3850 5450);
PAINT GREEN (-3850 5450);
DISPLAY INVISIBLE (-3850 5450);
FORCEPROP 2 LAST SEC 1
J 0
(-4000 5400);
DISPLAY 0.680851 (-4000 5400);
PAINT MONO (-4000 5400);
DISPLAY INVISIBLE (-4000 5400);
FORCEPROP 2 LAST SEC_TYPE DISCRET-G
J 0
(-4000 5400);
DISPLAY 1.021277 (-4000 5400);
PAINT ORANGE (-4000 5400);
DISPLAY INVISIBLE (-4000 5400);
FORCEPROP 1 LAST PART_NUMBER 68.00084.921
R 1
J 0
(-3849 5450);
DISPLAY 0.617021 (-3849 5450);
PAINT GREEN (-3849 5450);
DISPLAY INVISIBLE (-3849 5450);
FORCEPROP 2 LAST CDS_LIB w_hdl
R 1
J 0
(-3850 5450);
DISPLAY INVISIBLE (-3850 5450);
FORCEPROP 1 LAST CDS_LMAN_SYM_OUTLINE -50,100,50,-100
R 1
J 0
(-3850 5450);
DISPLAY 0.468085 (-3850 5450);
PAINT GREEN (-3850 5450);
DISPLAY INVISIBLE (-3850 5450);
FORCEADD TTL1G126_A..1
R 6
(-7850 4750);
FORCEPROP 1 LASTPIN (-7850 4850) $PN 1
J 0
(-7845 4871);
DISPLAY 0.617021 (-7845 4871);
PAINT WHITE (-7845 4871);
FORCEPROP 1 LAST VALUE 74HC1G126
J 0
(-7900 4621);
DISPLAY 0.617021 (-7900 4621);
PAINT SKYBLUE (-7900 4621);
FORCEPROP 1 LASTPIN (-8000 4750) $PN 2
J 2
(-7975 4711);
DISPLAY 0.617021 (-7975 4711);
PAINT WHITE (-7975 4711);
FORCEPROP 1 LASTPIN (-7700 4750) $PN 4
J 0
(-7735 4711);
DISPLAY 0.617021 (-7735 4711);
PAINT WHITE (-7735 4711);
FORCEPROP 1 LAST POWER_GROUP VCC=P3V3_STBY;GND=GND;
J 0
(-7750 4861);
DISPLAY 0.617021 (-7750 4861);
PAINT ORANGE (-7750 4861);
FORCEPROP 1 LAST PART_NUMBER A79322-001
J 0
(-7750 4811);
DISPLAY 0.617021 (-7750 4811);
PAINT BLUE (-7750 4811);
FORCEPROP 1 LAST MATERIAL IC
J 0
(-7900 4571);
DISPLAY 0.617021 (-7900 4571);
PAINT SKYBLUE (-7900 4571);
FORCEPROP 1 LAST LOCATION U25W19
J 0
(-7900 4521);
DISPLAY 0.617021 (-7900 4521);
PAINT AQUA (-7900 4521);
FORCEPROP 2 LAST BOM_COST SB
J 0
(-7900 4402);
DISPLAY 1.021277 (-7900 4402);
PAINT ORANGE (-7900 4402);
DISPLAY INVISIBLE (-7900 4402);
FORCEPROP 2 LAST SEC_TYPE SOT
J 0
(-7900 4452);
DISPLAY 1.021277 (-7900 4452);
PAINT ORANGE (-7900 4452);
DISPLAY INVISIBLE (-7900 4452);
FORCEPROP 2 LAST CDS_LIB mstr_ttl
J 0
(-7850 4703);
PAINT MONO (-7850 4703);
DISPLAY INVISIBLE (-7850 4703);
FORCEPROP 2 LAST SEC 1
J 0
(-7900 4468);
DISPLAY 0.680851 (-7900 4468);
PAINT MONO (-7900 4468);
DISPLAY INVISIBLE (-7900 4468);
FORCEPROP 2 LAST ROOM SB
J 0
(-7900 4452);
DISPLAY 1.021277 (-7900 4452);
PAINT ORANGE (-7900 4452);
DISPLAY INVISIBLE (-7900 4452);
FORCEPROP 1 LAST PACK_TYPE SOT
J 0
(-7900 4454);
DISPLAY 0.978723 (-7900 4454);
PAINT SKYBLUE (-7900 4454);
DISPLAY INVISIBLE (-7900 4454);
FORCEPROP 1 LAST PATH I76
J 2
(-7955 4604);
DISPLAY 0.978723 (-7955 4604);
PAINT GREEN (-7955 4604);
DISPLAY INVISIBLE (-7955 4604);
FORCEPROP 2 LAST CDS_LOCATION U25W19
J 0
(-7900 4521);
DISPLAY 0.617021 (-7900 4521);
PAINT AQUA (-7900 4521);
DISPLAY INVISIBLE (-7900 4521);
FORCEADD OFFPAGE..1
(-8650 4750);
FORCEPROP 2 LAST $XR1 189 
J 0
(-9052 4750);
DISPLAY 0.638298 (-9052 4750);
PAINT MONO (-9052 4750);
FORCEPROP 2 LAST $XR0 144 
J 0
(-8932 4750);
DISPLAY 0.638298 (-8932 4750);
PAINT MONO (-8932 4750);
FORCEPROP 2 LAST PATH I77
J 0
(-8900 4800);
DISPLAY 1.021277 (-8900 4800);
PAINT ORANGE (-8900 4800);
DISPLAY INVISIBLE (-8900 4800);
FORCEPROP 2 LAST CDS_LIB mstr_standard
J 0
(-8650 4750);
PAINT ORANGE (-8650 4750);
DISPLAY INVISIBLE (-8650 4750);
FORCEPROP 1 LAST OFFPAGE TRUE
J 0
(-8325 4625);
DISPLAY 1.404255 (-8325 4625);
PAINT GREEN (-8325 4625);
DISPLAY INVISIBLE (-8325 4625);
FORCEPROP 1 LAST COMMENT_BODY TRUE
J 0
(-8525 4650);
DISPLAY 1.404255 (-8525 4650);
PAINT PEACH (-8525 4650);
DISPLAY INVISIBLE (-8525 4650);
FORCEADD GND..1
(-7050 4525);
FORCEPROP 3 LASTPIN (-7050 4575) SIG_NAME GND\g
J 0
(-7040 4585);
DISPLAY 0.659574 (-7040 4585);
PAINT MONO (-7040 4585);
DISPLAY INVISIBLE (-7040 4585);
FORCEPROP 1 LAST SIZE 1B
J 0
(-6975 4475);
DISPLAY 0.872340 (-6975 4475);
PAINT AQUA (-6975 4475);
DISPLAY INVISIBLE (-6975 4475);
FORCEPROP 1 LAST VOLTAGE 0.0V
J 0
(-7095 4482);
DISPLAY 0.340426 (-7095 4482);
PAINT SKYBLUE (-7095 4482);
DISPLAY INVISIBLE (-7095 4482);
FORCEPROP 2 LAST CDS_LIB mstr_symbols
J 0
(-7050 4525);
PAINT ORANGE (-7050 4525);
DISPLAY INVISIBLE (-7050 4525);
FORCEPROP 1 LAST PATH I78
J 0
(-6975 4525);
DISPLAY 0.872340 (-6975 4525);
PAINT AQUA (-6975 4525);
DISPLAY INVISIBLE (-6975 4525);
FORCEPROP 1 LAST BODY_TYPE PLUMBING
J 0
(-7095 4482);
DISPLAY 0.340426 (-7095 4482);
PAINT GREEN (-7095 4482);
DISPLAY INVISIBLE (-7095 4482);
FORCEPROP 1 LAST HDL_POWER GND
J 0
(-7050 4675);
DISPLAY 0.872340 (-7050 4675);
PAINT GREEN (-7050 4675);
DISPLAY INVISIBLE (-7050 4675);
FORCEADD CAP_A..1
(-7050 4700);
FORCEPROP 1 LAST LOCATION C25W101
J 0
(-7000 4800);
DISPLAY 0.617021 (-7000 4800);
PAINT AQUA (-7000 4800);
FORCEPROP 1 LAST VALUE 0.1UF
J 0
(-7000 4750);
DISPLAY 0.617021 (-7000 4750);
PAINT SKYBLUE (-7000 4750);
FORCEPROP 1 LAST VOLTAGE 16V
J 0
(-7000 4700);
DISPLAY 0.617021 (-7000 4700);
PAINT SKYBLUE (-7000 4700);
FORCEPROP 1 LAST TOLERANCE 10%
J 0
(-7000 4650);
DISPLAY 0.617021 (-7000 4650);
PAINT SKYBLUE (-7000 4650);
FORCEPROP 1 LAST PACK_TYPE 0402V
J 0
(-7000 4500);
DISPLAY 0.617021 (-7000 4500);
PAINT SKYBLUE (-7000 4500);
FORCEPROP 1 LAST MATERIAL X7R
J 0
(-7000 4600);
DISPLAY 0.617021 (-7000 4600);
PAINT SKYBLUE (-7000 4600);
FORCEPROP 1 LASTPIN (-7050 4800) $PN 1
J 0
(-7040 4780);
DISPLAY 0.617021 (-7040 4780);
PAINT ORANGE (-7040 4780);
FORCEPROP 1 LAST PART_NUMBER A36096-030
J 0
(-7000 4550);
DISPLAY 0.617021 (-7000 4550);
PAINT BLUE (-7000 4550);
FORCEPROP 1 LASTPIN (-7050 4600) $PN 2
J 0
(-7040 4580);
DISPLAY 0.617021 (-7040 4580);
PAINT ORANGE (-7040 4580);
FORCEPROP 2 LAST ROOM UART_MUX
J 0
(-7000 4850);
DISPLAY 1.021277 (-7000 4850);
PAINT ORANGE (-7000 4850);
DISPLAY INVISIBLE (-7000 4850);
FORCEPROP 2 LAST SEC 1
J 0
(-7000 4900);
DISPLAY 0.680851 (-7000 4900);
PAINT MONO (-7000 4900);
DISPLAY INVISIBLE (-7000 4900);
FORCEPROP 2 LAST CDS_SEC 1
J 0
(-7000 4850);
PAINT ORANGE (-7000 4850);
DISPLAY INVISIBLE (-7000 4850);
FORCEPROP 2 LAST BOM_COST DEBUG
J 0
(-7000 4900);
DISPLAY 1.021277 (-7000 4900);
PAINT ORANGE (-7000 4900);
DISPLAY INVISIBLE (-7000 4900);
FORCEPROP 2 LAST SEC_TYPE 0402V
J 0
(-7000 4900);
DISPLAY 1.021277 (-7000 4900);
PAINT ORANGE (-7000 4900);
DISPLAY INVISIBLE (-7000 4900);
FORCEPROP 2 LAST CDS_LIB dev_discrete
J 0
(-7050 4700);
PAINT ORANGE (-7050 4700);
DISPLAY INVISIBLE (-7050 4700);
FORCEPROP 1 LAST PATH I79
J 0
(-7000 4850);
DISPLAY 0.978723 (-7000 4850);
PAINT WHITE (-7000 4850);
DISPLAY INVISIBLE (-7000 4850);
FORCEPROP 2 LAST CDS_LOCATION C25W101
J 0
(-7000 4800);
DISPLAY 0.617021 (-7000 4800);
PAINT AQUA (-7000 4800);
DISPLAY INVISIBLE (-7000 4800);
FORCEADD P3V3_STBY..1
(-7050 4900);
FORCEPROP 3 LASTPIN (-7050 4850) SIG_NAME P3V3_STBY\g
J 0
(-7040 4860);
DISPLAY 0.659574 (-7040 4860);
PAINT MONO (-7040 4860);
DISPLAY INVISIBLE (-7040 4860);
FORCEPROP 1 LAST VOLTAGE 3.3V
J 0
(-7095 4857);
DISPLAY 0.340426 (-7095 4857);
PAINT SKYBLUE (-7095 4857);
DISPLAY INVISIBLE (-7095 4857);
FORCEPROP 2 LAST CDS_LIB mstr_symbols
J 0
(-7050 4900);
PAINT MONO (-7050 4900);
DISPLAY INVISIBLE (-7050 4900);
FORCEPROP 1 LAST SIZE 1B
J 0
(-7005 4922);
DISPLAY 0.340426 (-7005 4922);
PAINT GREEN (-7005 4922);
DISPLAY INVISIBLE (-7005 4922);
FORCEPROP 1 LAST PATH I80
J 0
(-7005 4902);
DISPLAY 0.340426 (-7005 4902);
PAINT GREEN (-7005 4902);
DISPLAY INVISIBLE (-7005 4902);
FORCEPROP 1 LAST BODY_TYPE PLUMBING
J 0
(-7095 4857);
DISPLAY 0.340426 (-7095 4857);
PAINT GREEN (-7095 4857);
DISPLAY INVISIBLE (-7095 4857);
FORCEPROP 1 LAST HDL_POWER P3V3_STBY
J 0
(-7350 4775);
DISPLAY 0.872340 (-7350 4775);
PAINT ORANGE (-7350 4775);
DISPLAY INVISIBLE (-7350 4775);
FORCEADD OFFPAGE..1
(-8650 4900);
FORCEPROP 2 LAST $XR1 254 
J 0
(-9052 4900);
DISPLAY 0.638298 (-9052 4900);
PAINT MONO (-9052 4900);
FORCEPROP 2 LAST $XR0 255 
J 0
(-8932 4900);
DISPLAY 0.638298 (-8932 4900);
PAINT MONO (-8932 4900);
FORCEPROP 2 LAST PATH I81
J 0
(-8900 4950);
DISPLAY 1.021277 (-8900 4950);
PAINT ORANGE (-8900 4950);
DISPLAY INVISIBLE (-8900 4950);
FORCEPROP 2 LAST CDS_LIB mstr_standard
J 0
(-8650 4900);
PAINT ORANGE (-8650 4900);
DISPLAY INVISIBLE (-8650 4900);
FORCEPROP 1 LAST OFFPAGE TRUE
J 0
(-8325 4775);
DISPLAY 1.404255 (-8325 4775);
PAINT GREEN (-8325 4775);
DISPLAY INVISIBLE (-8325 4775);
FORCEPROP 1 LAST COMMENT_BODY TRUE
J 0
(-8525 4800);
DISPLAY 1.404255 (-8525 4800);
PAINT PEACH (-8525 4800);
DISPLAY INVISIBLE (-8525 4800);
FORCEADD INTEL_CORP_BPAGE..1
(-1400 1825);
FORCEPROP 1 LAST CDS_CON_LAST_MODIFIED Fri Jun 16 17:49:32 2017
J 0
(-2825 2150);
PAINT ORANGE (-2825 2150);
DISPLAY INVISIBLE (-2825 2150);
FORCEPROP 2 LAST CUSTOM_TXT_CDS <XR_PAGE_TITLE>
J 0
(-9290 7075);
DISPLAY 0.638298 (-9290 7075);
PAINT PINK (-9290 7075);
DISPLAY INVISIBLE (-9290 7075);
FORCEPROP 2 LAST CUSTOM_TXT_CDS <CON_LAST_MODIFIED>
J 0
(-5400 1925);
PAINT ORANGE (-5400 1925);
FORCEPROP 2 LAST CUSTOM_TXT_CDS <CURRENT_DESIGN_SHEET> OF <TOTAL_DESIGN_SHEETS>
J 0
(-1900 1850);
PAINT ORANGE (-1900 1850);
FORCEPROP 1 LAST SCH_TITLE BMC REMOTE DEBUG CIRCUIT - 1 OF 2
J 0
(-9350 1875);
DISPLAY 2.468085 (-9350 1875);
PAINT ORANGE (-9350 1875);
FORCEPROP 2 LAST CDS_LIB mstr_symbols
J 0
(-1400 1825);
PAINT MONO (-1400 1825);
DISPLAY INVISIBLE (-1400 1825);
FORCEPROP 2 LAST PAGE_BORDER TRUE
J 0
(-9290 7075);
DISPLAY 0.638298 (-9290 7075);
PAINT PINK (-9290 7075);
DISPLAY INVISIBLE (-9290 7075);
FORCEPROP 1 LAST COMMENT_BODY TRUE
J 0
(-1388 1837);
DISPLAY 0.468085 (-1388 1837);
PAINT GREEN (-1388 1837);
DISPLAY INVISIBLE (-1388 1837);
FORCEPROP 2 LAST CDS_XR_PAGE_TITLE CR-254 : @BASEBOARD_FAB2_LIB.BASEBOARD_FAB2(SCH_1):PAGE254
J 0
(-9290 7075);
DISPLAY 0.638298 (-9290 7075);
PAINT PINK (-9290 7075);
DISPLAY INVISIBLE (-9290 7075);
FORCEADD CAD_NOTE..1
(-4900 4650);
FORCEPROP 0 LAST L1 PLACE CAP CLOSE TO
J 0
(-5050 4500);
DISPLAY 1.021277 (-5050 4500);
PAINT ORANGE (-5050 4500);
FORCEPROP 0 LAST L2 U25E17
J 0
(-5050 4450);
DISPLAY 1.021277 (-5050 4450);
PAINT ORANGE (-5050 4450);
FORCEPROP 2 LAST CDS_LIB mstr_symbols
J 0
(-4900 4650);
PAINT ORANGE (-4900 4650);
DISPLAY INVISIBLE (-4900 4650);
FORCEPROP 1 LAST COMMENT_BODY TRUE
J 0
(-4875 4750);
DISPLAY 0.978723 (-4875 4750);
PAINT ORANGE (-4875 4750);
DISPLAY INVISIBLE (-4875 4750);
WIRE 16 -1 (-4100 3475)(-4100 3500);
WIRE 16 -1 (-4100 3700)(-4100 3500);
WIRE 16 -1 (-4650 3500)(-4100 3500);
WIRE 16 -1 (-4100 3900)(-4100 3700);
WIRE 16 -1 (-4650 3700)(-4100 3700);
WIRE 16 -1 (-4650 3900)(-4100 3900);
WIRE 16 -1 (-6400 3950)(-6400 4050);
WIRE 16 -1 (-6200 6000)(-6200 5925);
WIRE 16 -1 (-6150 6000)(-6200 6000);
WIRE 16 -1 (-7650 6250)(-7650 6300);
WIRE 16 -1 (-7650 6250)(-7350 6250);
WIRE 16 -1 (-7650 6250)(-7650 6150);
WIRE 16 -1 (-7350 6250)(-7050 6250);
WIRE 16 -1 (-7350 6250)(-7350 6150);
WIRE 16 -1 (-6750 6250)(-7050 6250);
WIRE 16 -1 (-7050 6250)(-7050 6150);
WIRE 16 -1 (-6750 6250)(-6450 6250);
WIRE 16 -1 (-6750 6250)(-6750 6150);
WIRE 16 -1 (-5800 6250)(-6450 6250);
WIRE 16 -1 (-6450 6150)(-6450 6250);
WIRE 16 -1 (-5500 6250)(-5800 6250);
WIRE 16 -1 (-5800 6150)(-5800 6250);
WIRE 16 -1 (-5500 6250)(-5500 5800);
WIRE 16 -1 (-5500 5800)(-5400 5800);
WIRE 16 -1 (-5800 5925)(-5800 5950);
WIRE 16 -1 (-4000 4300)(-4000 4100);
WIRE 16 -1 (-4000 4100)(-4000 3900);
WIRE 16 -1 (-4000 4100)(-3900 4100);
WIRE 16 -1 (-4000 3900)(-4000 3700);
WIRE 16 -1 (-4000 3900)(-3900 3900);
WIRE 16 -1 (-3900 3700)(-4000 3700);
WIRE 16 -1 (-4400 5100)(-4400 5075);
WIRE 16 -1 (-4400 5150)(-4400 5100);
WIRE 16 -1 (-4500 5100)(-4400 5100);
WIRE 16 -1 (-4400 5200)(-4400 5150);
WIRE 16 -1 (-4500 5150)(-4400 5150);
WIRE 16 -1 (-4500 5200)(-4400 5200);
WIRE 16 -1 (-3050 2900)(-3050 2875);
WIRE 16 -1 (-6600 3550)(-6600 3525);
WIRE 16 -1 (-6600 3600)(-6600 3550);
WIRE 16 -1 (-6700 3550)(-6600 3550);
WIRE 16 -1 (-6700 3600)(-6600 3600);
WIRE 16 -1 (-8700 3750)(-8700 3725);
WIRE 16 -1 (-8700 4100)(-8700 4050);
WIRE 16 -1 (-8700 4050)(-8300 4050);
WIRE 16 -1 (-8700 4050)(-8700 3950);
WIRE 16 -1 (-8300 4050)(-8300 3650);
WIRE 16 -1 (-8300 3650)(-7450 3650);
WIRE 16 -1 (-3050 3150)(-3050 3100);
WIRE 16 -1 (-5350 4350)(-5350 4325);
WIRE 16 -1 (-5350 4600)(-5350 4550);
WIRE 16 -1 (-5650 2900)(-5650 2875);
WIRE 16 -1 (-6000 2900)(-5650 2900);
WIRE 16 -1 (-7050 4600)(-7050 4575);
WIRE 16 -1 (-7050 4800)(-7050 4850);
WIRE 16 -1 (-7650 5350)(-7700 5350);
WIRE 16 -1 (-7650 5950)(-7650 5350);
WIRE 16 -1 (-5400 5350)(-7650 5350);
FORCEPROP 2 LAST SIG_NAME BMC_PREQ_BUF_N
J 0
(-6685 5360);
DISPLAY 0.638298 (-6685 5360);
PAINT ORANGE (-6685 5360);
WIRE 16 -1 (-6450 5650)(-5400 5650);
FORCEPROP 2 LAST SIG_NAME PU_GTL2014_3_DIR
J 0
(-5885 5660);
DISPLAY 0.617021 (-5885 5660);
PAINT ORANGE (-5885 5660);
FORCEPROP 2 LASTPROP $XRERR UNIQUE?
J 0
(-6125 5660);
DISPLAY 0.638298 (-6125 5660);
PAINT MONO (-6125 5660);
DISPLAY INVISIBLE (-6125 5660);
WIRE 16 -1 (-6450 5950)(-6450 5650);
WIRE 16 -1 (-6600 3700)(-6700 3700);
WIRE 16 -1 (-6600 4000)(-6600 3700);
WIRE 16 -1 (-6600 4000)(-7650 4000);
FORCEPROP 2 LAST SIG_NAME JTAG_BMC_TCK_BUF
J 0
(-7060 4010);
DISPLAY 0.638298 (-7060 4010);
PAINT ORANGE (-7060 4010);
FORCEPROP 2 LASTPROP $XRERR UNIQUE?
J 0
(-7300 4010);
DISPLAY 0.638298 (-7300 4010);
PAINT MONO (-7300 4010);
DISPLAY INVISIBLE (-7300 4010);
WIRE 16 -1 (-7650 4750)(-7650 4000);
WIRE 16 -1 (-7700 4750)(-7650 4750);
WIRE 3 682 (-7500 4150)(-7450 4150);
WIRE 3 682 (-7450 4050)(-7500 4050);
WIRE 3 682 (-7500 4050)(-7500 4150);
WIRE 3 682 (-6050 5000)(-8050 5000);
WIRE 3 682 (-6050 4450)(-6050 5000);
WIRE 3 682 (-8050 5000)(-8050 4450);
WIRE 3 682 (-8050 4450)(-6050 4450);
WIRE 16 -1 (-6400 3750)(-6400 3650);
WIRE 16 -1 (-6550 3650)(-6700 3650);
WIRE 16 -1 (-6400 3650)(-6550 3650);
WIRE 16 -1 (-6550 4050)(-6550 3650);
WIRE 16 -1 (-7100 4050)(-6550 4050);
FORCEPROP 2 LAST SIG_NAME BMC_JTAG_SEL_N
J 0
(-7035 4060);
DISPLAY 0.638298 (-7035 4060);
PAINT ORANGE (-7035 4060);
WIRE 3 682 (-6100 3450)(-6100 3200);
WIRE 3 682 (-5000 3450)(-6100 3450);
WIRE 3 682 (-6100 3200)(-5000 3200);
WIRE 3 682 (-5000 3200)(-5000 3450);
WIRE 3 682 (-6450 3350)(-6950 3350);
WIRE 3 682 (-6450 3100)(-6450 3350);
WIRE 3 682 (-6950 3350)(-6950 3100);
WIRE 3 682 (-6950 3100)(-6450 3100);
WIRE 16 -1 (-4850 3700)(-4900 3700);
WIRE 16 -1 (-4900 3700)(-4900 3800);
WIRE 16 -1 (-3900 3800)(-4900 3800);
WIRE 16 -1 (-5750 3800)(-4900 3800);
FORCEPROP 2 LAST SIG_NAME JTAG_BMC_TCK1
J 0
(-5685 3810);
DISPLAY 0.638298 (-5685 3810);
PAINT ORANGE (-5685 3810);
FORCEPROP 2 LASTPROP $XR0 254 
J 0
(-5876 3800);
DISPLAY 0.638298 (-5876 3800);
PAINT MONO (-5876 3800);
WIRE 3 682 (-4050 3450)(-4050 3125);
WIRE 3 682 (-3800 3450)(-4050 3450);
WIRE 3 682 (-4050 3750)(-4050 3450);
WIRE 3 682 (-3800 3450)(-3800 3750);
WIRE 3 682 (-3800 3750)(-4050 3750);
WIRE 3 682 (-9250 6650)(-9250 2700);
WIRE 3 682 (-1500 6650)(-9250 6650);
WIRE 3 682 (-9250 2700)(-1500 2700);
WIRE 3 682 (-1500 2700)(-1500 6650);
WIRE 16 -1 (-4500 5500)(-3700 5500);
FORCEPROP 2 LAST SIG_NAME XDP_TMS_R
J 0
(-4385 5510);
DISPLAY 0.638298 (-4385 5510);
PAINT ORANGE (-4385 5510);
FORCEPROP 2 LASTPROP $XRERR UNIQUE?
J 0
(-4625 5510);
DISPLAY 0.638298 (-4625 5510);
PAINT MONO (-4625 5510);
DISPLAY INVISIBLE (-4625 5510);
WIRE 16 -1 (-4500 5450)(-4000 5450);
FORCEPROP 2 LAST SIG_NAME XDP_TDI_R
J 0
(-4385 5460);
DISPLAY 0.638298 (-4385 5460);
PAINT ORANGE (-4385 5460);
FORCEPROP 2 LASTPROP $XRERR UNIQUE?
J 0
(-4625 5460);
DISPLAY 0.638298 (-4625 5460);
PAINT MONO (-4625 5460);
DISPLAY INVISIBLE (-4625 5460);
WIRE 16 -1 (-5950 6000)(-5900 6000);
WIRE 16 -1 (-5900 5750)(-5900 6000);
WIRE 16 -1 (-5900 5750)(-5400 5750);
FORCEPROP 2 LAST SIG_NAME PD_GTL2014_3_VREF
J 0
(-5885 5760);
DISPLAY 0.617021 (-5885 5760);
PAINT ORANGE (-5885 5760);
FORCEPROP 2 LASTPROP $XRERR UNIQUE?
J 0
(-6125 5760);
DISPLAY 0.638298 (-6125 5760);
PAINT MONO (-6125 5760);
DISPLAY INVISIBLE (-6125 5760);
WIRE 16 -1 (-7450 3700)(-8100 3700);
FORCEPROP 2 LAST SIG_NAME JTAG_BMC_TCK0
J 0
(-8035 3710);
DISPLAY 0.638298 (-8035 3710);
PAINT ORANGE (-8035 3710);
FORCEPROP 2 LASTPROP $XR0 254 
J 0
(-8196 3700);
DISPLAY 0.638298 (-8196 3700);
PAINT MONO (-8196 3700);
WIRE 3 682 (-3250 3300)(-3250 3050);
WIRE 3 682 (-2800 3300)(-3250 3300);
WIRE 3 682 (-3250 3050)(-2800 3050);
WIRE 3 682 (-2800 3050)(-2800 3300);
WIRE 16 -1 (-2650 3900)(-2150 3900);
FORCEPROP 2 LAST SIG_NAME XDP_PCH_TCK1
J 0
(-2585 3910);
DISPLAY 0.638298 (-2585 3910);
PAINT ORANGE (-2585 3910);
WIRE 16 -1 (-2650 3700)(-2150 3700);
FORCEPROP 2 LAST SIG_NAME XDP_CPU_TCK0
J 0
(-2585 3710);
DISPLAY 0.638298 (-2585 3710);
PAINT ORANGE (-2585 3710);
WIRE 16 -1 (-3500 3500)(-2150 3500);
FORCEPROP 2 LAST SIG_NAME BMC_PREQ_BUF_N
J 0
(-3385 3510);
DISPLAY 0.638298 (-3385 3510);
PAINT ORANGE (-3385 3510);
WIRE 16 -1 (-3500 4100)(-2950 4100);
FORCEPROP 2 LAST SIG_NAME XDP_TRST_R_N
J 0
(-3385 4110);
DISPLAY 0.638298 (-3385 4110);
PAINT ORANGE (-3385 4110);
FORCEPROP 2 LASTPROP $XRERR UNIQUE?
J 0
(-3625 4110);
DISPLAY 0.638298 (-3625 4110);
PAINT MONO (-3625 4110);
DISPLAY INVISIBLE (-3625 4110);
WIRE 16 -1 (-5250 4050)(-5750 4050);
FORCEPROP 2 LAST SIG_NAME JTAG_BMC_TRST_N
J 0
(-5735 4060);
DISPLAY 0.638298 (-5735 4060);
PAINT ORANGE (-5735 4060);
WIRE 16 -1 (-5750 3950)(-5250 3950);
FORCEPROP 2 LAST SIG_NAME BMC_JTAG_SEL_BUF
J 0
(-5727 3971);
DISPLAY 0.638298 (-5727 3971);
PAINT ORANGE (-5727 3971);
WIRE 16 -1 (-2650 4100)(-2150 4100);
FORCEPROP 2 LAST SIG_NAME XDP_TRST_N
J 0
(-2585 4110);
DISPLAY 0.638298 (-2585 4110);
PAINT ORANGE (-2585 4110);
WIRE 3 682 (-2850 3650)(-2750 3650);
WIRE 3 682 (-2850 4150)(-2850 3650);
WIRE 3 682 (-2750 3650)(-2750 4150);
WIRE 3 682 (-2750 4150)(-2850 4150);
WIRE 16 -1 (-3500 3900)(-2950 3900);
FORCEPROP 2 LAST SIG_NAME XDP_PCH_TCK1_R
J 0
(-3385 3910);
DISPLAY 0.638298 (-3385 3910);
PAINT ORANGE (-3385 3910);
FORCEPROP 2 LASTPROP $XRERR UNIQUE?
J 0
(-3625 3910);
DISPLAY 0.638298 (-3625 3910);
PAINT MONO (-3625 3910);
DISPLAY INVISIBLE (-3625 3910);
WIRE 16 -1 (-3500 3700)(-2950 3700);
FORCEPROP 2 LAST SIG_NAME XDP_CPU_TCK0_R
J 0
(-3385 3710);
DISPLAY 0.638298 (-3385 3710);
PAINT ORANGE (-3385 3710);
FORCEPROP 2 LASTPROP $XRERR UNIQUE?
J 0
(-3625 3710);
DISPLAY 0.638298 (-3625 3710);
PAINT MONO (-3625 3710);
DISPLAY INVISIBLE (-3625 3710);
WIRE 16 -1 (-3950 3300)(-5750 3300);
FORCEPROP 2 LAST SIG_NAME BMC_JTAG_SEL_BUF
J 0
(-5685 3310);
DISPLAY 0.638298 (-5685 3310);
PAINT ORANGE (-5685 3310);
WIRE 16 -1 (-3950 3400)(-3950 3300);
WIRE 16 -1 (-3900 3400)(-3950 3400);
WIRE 16 -1 (-4000 3350)(-5750 3350);
FORCEPROP 2 LAST SIG_NAME BMC_PREQ_N
J 0
(-5685 3360);
DISPLAY 0.638298 (-5685 3360);
PAINT ORANGE (-5685 3360);
WIRE 16 -1 (-4000 3500)(-4000 3350);
WIRE 16 -1 (-4000 3500)(-3900 3500);
WIRE 16 -1 (-4850 3500)(-4900 3500);
WIRE 16 -1 (-4900 3600)(-5750 3600);
FORCEPROP 2 LAST SIG_NAME JTAG_BMC_TCK0
J 0
(-5685 3610);
DISPLAY 0.638298 (-5685 3610);
PAINT ORANGE (-5685 3610);
FORCEPROP 2 LASTPROP $XR0 254 
J 0
(-5876 3600);
DISPLAY 0.638298 (-5876 3600);
PAINT MONO (-5876 3600);
WIRE 16 -1 (-4900 3500)(-4900 3600);
WIRE 16 -1 (-3900 3600)(-4900 3600);
WIRE 16 -1 (-4850 3900)(-4900 3900);
WIRE 16 -1 (-4950 4000)(-4900 4000);
WIRE 16 -1 (-4900 3900)(-4900 4000);
WIRE 16 -1 (-3900 4000)(-4900 4000);
FORCEPROP 2 LAST SIG_NAME JTAG_BMC_TRST_BUF_N
J 0
(-4860 4010);
DISPLAY 0.638298 (-4860 4010);
PAINT ORANGE (-4860 4010);
FORCEPROP 2 LASTPROP $XRERR UNIQUE?
J 0
(-5100 4010);
DISPLAY 0.638298 (-5100 4010);
PAINT MONO (-5100 4010);
DISPLAY INVISIBLE (-5100 4010);
WIRE 16 -1 (-2650 5350)(-4500 5350);
FORCEPROP 2 LAST SIG_NAME XDP_PREQ_N
J 0
(-3185 5360);
DISPLAY 0.638298 (-3185 5360);
PAINT ORANGE (-3185 5360);
WIRE 16 -1 (-4500 5400)(-2650 5400);
FORCEPROP 2 LAST SIG_NAME XDP_CPU_PWR_DEBUG_N
J 0
(-3185 5410);
DISPLAY 0.638298 (-3185 5410);
PAINT ORANGE (-3185 5410);
WIRE 3 682 (-4025 5575)(-4025 5425);
WIRE 3 682 (-3375 5575)(-4025 5575);
WIRE 3 682 (-4025 5425)(-3375 5425);
WIRE 3 682 (-3375 5425)(-3375 5575);
WIRE 16 -1 (-3700 5450)(-2650 5450);
FORCEPROP 2 LAST SIG_NAME XDP_TDI
J 0
(-3185 5460);
DISPLAY 0.638298 (-3185 5460);
PAINT ORANGE (-3185 5460);
WIRE 16 -1 (-3400 5500)(-2650 5500);
FORCEPROP 2 LAST SIG_NAME XDP_TMS
J 0
(-3185 5510);
DISPLAY 0.638298 (-3185 5510);
PAINT ORANGE (-3185 5510);
WIRE 3 682 (-3450 3550)(-3450 3450);
WIRE 3 682 (-2675 3550)(-3450 3550);
WIRE 3 682 (-3450 3450)(-2675 3450);
WIRE 3 682 (-2675 3450)(-2675 3550);
WIRE 16 -1 (-8100 3550)(-7450 3550);
FORCEPROP 2 LAST SIG_NAME JTAG_BMC_TCK1
J 0
(-8035 3560);
DISPLAY 0.638298 (-8035 3560);
PAINT ORANGE (-8035 3560);
FORCEPROP 2 LASTPROP $XR0 254 
J 0
(-8196 3550);
DISPLAY 0.638298 (-8196 3550);
PAINT MONO (-8196 3550);
WIRE 16 -1 (-7050 5950)(-7050 5450);
WIRE 16 -1 (-7050 5450)(-5400 5450);
FORCEPROP 2 LAST SIG_NAME JTAG_BMC_BUF_TDI
J 0
(-6682 5451);
DISPLAY 0.638298 (-6682 5451);
PAINT ORANGE (-6682 5451);
WIRE 16 -1 (-7700 5450)(-7050 5450);
WIRE 16 -1 (-6750 5950)(-6750 5500);
WIRE 16 -1 (-6750 5500)(-5400 5500);
WIRE 16 -1 (-7700 5500)(-6750 5500);
FORCEPROP 2 LAST SIG_NAME JTAG_BMC_BUF_TMS
J 0
(-6685 5510);
DISPLAY 0.638298 (-6685 5510);
PAINT ORANGE (-6685 5510);
WIRE 16 -1 (-7350 5400)(-7700 5400);
WIRE 16 -1 (-7350 5950)(-7350 5400);
WIRE 16 -1 (-5400 5400)(-7350 5400);
FORCEPROP 2 LAST SIG_NAME BMC_PWR_DEBUG_BUF_N
J 0
(-6685 5410);
DISPLAY 0.638298 (-6685 5410);
PAINT ORANGE (-6685 5410);
WIRE 16 -1 (-6200 2900)(-8300 2900);
WIRE 16 -1 (-8300 2900)(-8300 3600);
WIRE 16 -1 (-7450 3600)(-8300 3600);
WIRE 16 -1 (-8900 3600)(-8300 3600);
FORCEPROP 2 LAST SIG_NAME BMC_TCK_MUX_SEL
J 0
(-8835 3609);
DISPLAY 0.638298 (-8835 3609);
PAINT ORANGE (-8835 3609);
WIRE 3 682 (-8200 5200)(-8000 5200);
WIRE 3 682 (-8200 5450)(-8200 5200);
WIRE 3 682 (-8100 5450)(-8200 5450);
WIRE 3 682 (-8100 5450)(-8050 5450);
WIRE 3 682 (-8100 5500)(-8100 5450);
WIRE 3 682 (-8050 5500)(-8100 5500);
WIRE 3 682 (-8050 5400)(-8100 5400);
WIRE 3 682 (-8100 5350)(-8050 5350);
WIRE 3 682 (-8100 5400)(-8100 5350);
WIRE 3 682 (-8100 5350)(-8150 5350);
WIRE 3 682 (-8150 5350)(-8150 5250);
WIRE 3 682 (-8150 5250)(-8000 5250);
WIRE 16 -1 (-7850 4900)(-8600 4900);
FORCEPROP 2 LAST SIG_NAME BMC_JTAG_SEL_BUF
J 0
(-8560 4910);
DISPLAY 0.638298 (-8560 4910);
PAINT ORANGE (-8560 4910);
WIRE 16 -1 (-7850 4850)(-7850 4900);
WIRE 16 -1 (-8000 4750)(-8600 4750);
FORCEPROP 2 LAST SIG_NAME JTAG_BMC_TCK
J 0
(-8535 4760);
DISPLAY 0.638298 (-8535 4760);
PAINT ORANGE (-8535 4760);
WIRE 3 682 (-6100 3875)(-6000 3875);
WIRE 3 682 (-6100 3950)(-6100 3875);
WIRE 3 682 (-6050 3950)(-6100 3950);
WIRE 3 682 (-8200 4200)(-8200 4000);
WIRE 3 682 (-8200 4000)(-7700 4000);
DOT 1 (-4000 3900);
DOT 1 (-4900 3800);
DOT 1 (-4900 4000);
DOT 1 (-4000 4100);
DOT 1 (-4050 3450);
DOT 1 (-4100 3500);
DOT 1 (-6750 5500);
DOT 1 (-7050 5450);
DOT 1 (-6450 6250);
DOT 1 (-7350 6250);
DOT 1 (-7650 6250);
DOT 1 (-6750 6250);
DOT 1 (-7050 6250);
DOT 1 (-4400 5100);
DOT 1 (-5800 6250);
DOT 1 (-8100 5450);
DOT 1 (-6550 3650);
DOT 1 (-6600 3550);
DOT 1 (-4400 5150);
DOT 1 (-7350 5400);
DOT 1 (-7650 5350);
DOT 1 (-4100 3700);
DOT 1 (-4900 3600);
DOT 1 (-8700 4050);
DOT 1 (-8100 5350);
DOT 1 (-8300 3600);
FORCENOTE
TP FAB3-DVT CHANGE RES R25W162-163 TO BEAD FB25W4-5 20161117
(-4050 5775) 0;
DISPLAY LEFT (-4050 5775);
DISPLAY 0.638298 (-4050 5775);
PAINT RED (-4050 5775);
FORCENOTE
120OHM @ 100MHZ
(-3600 5700) 0;
DISPLAY LEFT (-3600 5700);
DISPLAY 0.638298 (-3600 5700);
PAINT PURPLE (-3600 5700);
FORCENOTE
120OHM @ 100MHZ
(-4100 5700) 0;
DISPLAY LEFT (-4100 5700);
DISPLAY 0.638298 (-4100 5700);
PAINT PURPLE (-4100 5700);
FORCENOTE
TP FAB3 ADD C25W99 AND U25W17 1021
(-5050 4300) 0;
DISPLAY LEFT (-5050 4300);
DISPLAY 0.638298 (-5050 4300);
PAINT RED (-5050 4300);
FORCENOTE
TP FAB3 CONNECT TO P1V05_PCH_STBY 1014
(-4325 3075) 0;
DISPLAY LEFT (-4325 3075);
DISPLAY 0.638298 (-4325 3075);
PAINT RED (-4325 3075);
FORCENOTE
120OHM @ 100MHZ
(-2950 4150) 0;
DISPLAY LEFT (-2950 4150);
DISPLAY 0.638298 (-2950 4150);
PAINT PURPLE (-2950 4150);
FORCENOTE
TP FAB3-DVT CHANGE RES R25W171-173 TO BEAD FB25W1-3 20161116
(-3100 4275) 0;
DISPLAY LEFT (-3100 4275);
DISPLAY 0.638298 (-3100 4275);
PAINT RED (-3100 4275);
FORCENOTE
120OHM @ 100MHZ
(-2950 3750) 0;
DISPLAY LEFT (-2950 3750);
DISPLAY 0.638298 (-2950 3750);
PAINT PURPLE (-2950 3750);
FORCENOTE
120OHM @ 100MHZ
(-2950 3950) 0;
DISPLAY LEFT (-2950 3950);
DISPLAY 0.638298 (-2950 3950);
PAINT PURPLE (-2950 3950);
FORCENOTE
TP FAB3 ADD BMC REMOTE CIRCUIT 0920
(-9225 2650) 0;
DISPLAY LEFT (-9225 2650);
DISPLAY 1.021277 (-9225 2650);
PAINT RED (-9225 2650);
FORCENOTE
TP FAB3 RECONNECT 1014
(-2775 3050) 0;
DISPLAY LEFT (-2775 3050);
DISPLAY 0.638298 (-2775 3050);
PAINT RED (-2775 3050);
FORCENOTE
TP FAB3 DISCONNECT FROM XDP_TDO 1014
(-3450 3375) 0;
DISPLAY LEFT (-3450 3375);
DISPLAY 0.638298 (-3450 3375);
PAINT RED (-3450 3375);
FORCENOTE
TP FAB3 CHANGE CONNECTION 1024
(-3450 3325) 0;
DISPLAY LEFT (-3450 3325);
DISPLAY 0.638298 (-3450 3325);
PAINT RED (-3450 3325);
FORCENOTE
TP FAB3 CHANGE CONNECTION 1024
(-7950 5225) 0;
DISPLAY LEFT (-7950 5225);
DISPLAY 0.638298 (-7950 5225);
PAINT RED (-7950 5225);
FORCENOTE
TP FAB3 RECONNECT 1014
(-7950 5175) 0;
DISPLAY LEFT (-7950 5175);
DISPLAY 0.638298 (-7950 5175);
PAINT RED (-7950 5175);
FORCENOTE
TP FAB3 RECONNECT 1014
(-8250 4325) 0;
DISPLAY LEFT (-8250 4325);
DISPLAY 0.638298 (-8250 4325);
PAINT RED (-8250 4325);
FORCENOTE
PLACE NEAR U25W19
(-6800 4850) 0;
DISPLAY LEFT (-6800 4850);
DISPLAY 1.021277 (-6800 4850);
PAINT PURPLE (-6800 4850);
FORCENOTE
TP FAB3 RECONNECT 1024
(-8250 4275) 0;
DISPLAY LEFT (-8250 4275);
DISPLAY 0.638298 (-8250 4275);
PAINT RED (-8250 4275);
FORCENOTE
TP FAB3-DVT CHANGE CONNECTION 20161108
(-6000 3875) 0;
DISPLAY LEFT (-6000 3875);
DISPLAY 0.638298 (-6000 3875);
PAINT RED (-6000 3875);
FORCENOTE
TP FAB3 CHANGE CONNECTION 1024
(-6100 3150) 0;
DISPLAY LEFT (-6100 3150);
DISPLAY 0.638298 (-6100 3150);
PAINT RED (-6100 3150);
FORCENOTE
TP FAB4 DELETE 3PIN HEADER J25W2 20170111
(-6950 3050) 0;
DISPLAY LEFT (-6950 3050);
DISPLAY 0.638298 (-6950 3050);
PAINT RED (-6950 3050);
FORCENOTE
TP FAB4 ADD BUFFER 20170111
(-6800 4400) 0;
DISPLAY LEFT (-6800 4400);
DISPLAY 0.638298 (-6800 4400);
PAINT RED (-6800 4400);
FORCENOTE
TP FAB3 RENAME 0922
(-7425 4150) 0;
DISPLAY LEFT (-7425 4150);
DISPLAY 0.638298 (-7425 4150);
PAINT RED (-7425 4150);
FORCENOTE
TP FAB4 REONNECT 20170111
(-8250 4225) 0;
DISPLAY LEFT (-8250 4225);
DISPLAY 0.638298 (-8250 4225);
PAINT RED (-8250 4225);
QUIT
